(kicad_sch
	(version 20250114)
	(generator "eeschema")
	(generator_version "9.0")
	(paper "A3")
	(title_block
		(title "Artix - Datacenter Secure Control Module (DC-SCM)")
		(date "2024-11-06")
		(rev "1.1.3")
	)
	(text "USB CLIENT"
		(exclude_from_sim no)
		(at 357.505 118.11 0)
		(effects
			(font
				(size 2 2)
				(thickness 0.5994)
				(bold yes)
			)
			(justify left bottom)
		)
	)
	(text "eMMC"
		(exclude_from_sim no)
		(at 88.265 224.79 0)
		(effects
			(font
				(size 2 2)
				(thickness 0.5994)
				(bold yes)
			)
			(justify left bottom)
		)
	)
	(text "Transceiver supply"
		(exclude_from_sim no)
		(at 22.225 18.415 0)
		(effects
			(font
				(size 2 2)
				(thickness 0.4)
				(bold yes)
			)
			(justify left bottom)
		)
	)
	(text "Pull up \nvia 10KOhm"
		(exclude_from_sim no)
		(at 64.135 177.8 0)
		(effects
			(font
				(size 1.27 1.27)
			)
			(justify left bottom)
		)
	)
	(text "PCIe x1"
		(exclude_from_sim no)
		(at 77.47 26.035 0)
		(effects
			(font
				(size 2 2)
				(thickness 0.5994)
				(bold yes)
			)
			(justify left bottom)
		)
	)
	(text "Debug USB"
		(exclude_from_sim no)
		(at 189.23 19.05 0)
		(effects
			(font
				(size 2 2)
				(thickness 0.5994)
				(bold yes)
			)
			(justify left bottom)
		)
	)
	(text "JTAG"
		(exclude_from_sim no)
		(at 244.475 46.355 0)
		(effects
			(font
				(size 2 2)
				(thickness 0.5994)
				(bold yes)
			)
			(justify left bottom)
		)
	)
	(text "HPM SPI"
		(exclude_from_sim no)
		(at 182.88 251.46 0)
		(effects
			(font
				(size 2 2)
				(thickness 0.5994)
				(bold yes)
			)
			(justify left bottom)
		)
	)
	(text "reserved for future use (as of DC-SCI OPC specification)"
		(exclude_from_sim no)
		(at 170.18 254.635 0)
		(effects
			(font
				(size 1.27 1.27)
			)
			(justify left bottom)
		)
	)
	(text "USB HOST"
		(exclude_from_sim no)
		(at 357.505 26.035 0)
		(effects
			(font
				(size 2 2)
				(thickness 0.5994)
				(bold yes)
			)
			(justify left bottom)
		)
	)
	(text "ESPI level translation"
		(exclude_from_sim no)
		(at 180.975 154.305 0)
		(effects
			(font
				(size 2 2)
				(thickness 0.5994)
				(bold yes)
			)
			(justify left bottom)
		)
	)
	(text "I3C voltage level translation"
		(exclude_from_sim no)
		(at 39.37 158.115 0)
		(effects
			(font
				(size 2 2)
				(thickness 0.5994)
				(bold yes)
			)
			(justify left bottom)
		)
	)
	(junction
		(at 125.73 267.97)
		(diameter 0)
		(color 0 0 0 0)
	)
	(junction
		(at 66.04 229.87)
		(diameter 0)
		(color 0 0 0 0)
	)
	(junction
		(at 118.11 262.89)
		(diameter 0)
		(color 0 0 0 0)
	)
	(junction
		(at 129.54 229.87)
		(diameter 0)
		(color 0 0 0 0)
	)
	(junction
		(at 181.61 21.59)
		(diameter 0)
		(color 0 0 0 0)
	)
	(junction
		(at 223.52 207.01)
		(diameter 0)
		(color 0 0 0 0)
	)
	(junction
		(at 130.81 21.59)
		(diameter 0)
		(color 0 0 0 0)
	)
	(junction
		(at 226.06 66.04)
		(diameter 0)
		(color 0 0 0 0)
	)
	(junction
		(at 175.26 21.59)
		(diameter 0)
		(color 0 0 0 0)
	)
	(junction
		(at 50.8 229.87)
		(diameter 0)
		(color 0 0 0 0)
	)
	(junction
		(at 137.16 275.59)
		(diameter 0)
		(color 0 0 0 0)
	)
	(junction
		(at 46.99 172.72)
		(diameter 0)
		(color 0 0 0 0)
	)
	(junction
		(at 243.84 58.42)
		(diameter 0)
		(color 0 0 0 0)
	)
	(junction
		(at 317.5 129.54)
		(diameter 0)
		(color 0 0 0 0)
	)
	(junction
		(at 313.69 173.99)
		(diameter 0)
		(color 0 0 0 0)
	)
	(junction
		(at 106.68 229.87)
		(diameter 0)
		(color 0 0 0 0)
	)
	(junction
		(at 34.29 36.83)
		(diameter 0)
		(color 0 0 0 0)
	)
	(junction
		(at 214.63 207.01)
		(diameter 0)
		(color 0 0 0 0)
	)
	(junction
		(at 167.64 39.37)
		(diameter 0)
		(color 0 0 0 0)
	)
	(junction
		(at 41.91 21.59)
		(diameter 0)
		(color 0 0 0 0)
	)
	(junction
		(at 387.35 48.26)
		(diameter 0)
		(color 0 0 0 0)
	)
	(junction
		(at 214.63 158.75)
		(diameter 0)
		(color 0 0 0 0)
	)
	(junction
		(at 129.54 270.51)
		(diameter 0)
		(color 0 0 0 0)
	)
	(junction
		(at 49.53 172.72)
		(diameter 0)
		(color 0 0 0 0)
	)
	(junction
		(at 43.18 229.87)
		(diameter 0)
		(color 0 0 0 0)
	)
	(junction
		(at 36.83 243.84)
		(diameter 0)
		(color 0 0 0 0)
	)
	(junction
		(at 261.62 31.75)
		(diameter 0)
		(color 0 0 0 0)
	)
	(junction
		(at 49.53 200.66)
		(diameter 0)
		(color 0 0 0 0)
	)
	(junction
		(at 48.26 21.59)
		(diameter 0)
		(color 0 0 0 0)
	)
	(junction
		(at 309.88 129.54)
		(diameter 0)
		(color 0 0 0 0)
	)
	(junction
		(at 114.3 260.35)
		(diameter 0)
		(color 0 0 0 0)
	)
	(junction
		(at 55.88 172.72)
		(diameter 0)
		(color 0 0 0 0)
	)
	(junction
		(at 161.29 54.61)
		(diameter 0)
		(color 0 0 0 0)
	)
	(junction
		(at 53.34 203.2)
		(diameter 0)
		(color 0 0 0 0)
	)
	(junction
		(at 386.08 116.84)
		(diameter 0)
		(color 0 0 0 0)
	)
	(junction
		(at 313.69 82.55)
		(diameter 0)
		(color 0 0 0 0)
	)
	(junction
		(at 41.91 36.83)
		(diameter 0)
		(color 0 0 0 0)
	)
	(junction
		(at 182.88 54.61)
		(diameter 0)
		(color 0 0 0 0)
	)
	(junction
		(at 86.36 172.72)
		(diameter 0)
		(color 0 0 0 0)
	)
	(junction
		(at 151.13 80.01)
		(diameter 0)
		(color 0 0 0 0)
	)
	(junction
		(at 264.16 36.83)
		(diameter 0)
		(color 0 0 0 0)
	)
	(junction
		(at 74.93 243.84)
		(diameter 0)
		(color 0 0 0 0)
	)
	(junction
		(at 55.88 21.59)
		(diameter 0)
		(color 0 0 0 0)
	)
	(junction
		(at 182.88 39.37)
		(diameter 0)
		(color 0 0 0 0)
	)
	(junction
		(at 154.94 25.4)
		(diameter 0)
		(color 0 0 0 0)
	)
	(junction
		(at 241.3 60.96)
		(diameter 0)
		(color 0 0 0 0)
	)
	(junction
		(at 63.5 36.83)
		(diameter 0)
		(color 0 0 0 0)
	)
	(junction
		(at 114.3 229.87)
		(diameter 0)
		(color 0 0 0 0)
	)
	(junction
		(at 121.92 229.87)
		(diameter 0)
		(color 0 0 0 0)
	)
	(junction
		(at 223.52 158.75)
		(diameter 0)
		(color 0 0 0 0)
	)
	(junction
		(at 57.15 243.84)
		(diameter 0)
		(color 0 0 0 0)
	)
	(junction
		(at 161.29 39.37)
		(diameter 0)
		(color 0 0 0 0)
	)
	(junction
		(at 213.36 128.27)
		(diameter 0)
		(color 0 0 0 0)
	)
	(junction
		(at 74.93 252.73)
		(diameter 0)
		(color 0 0 0 0)
	)
	(junction
		(at 146.05 125.73)
		(diameter 0)
		(color 0 0 0 0)
	)
	(junction
		(at 322.58 82.55)
		(diameter 0)
		(color 0 0 0 0)
	)
	(junction
		(at 153.67 54.61)
		(diameter 0)
		(color 0 0 0 0)
	)
	(junction
		(at 40.64 172.72)
		(diameter 0)
		(color 0 0 0 0)
	)
	(junction
		(at 326.39 38.1)
		(diameter 0)
		(color 0 0 0 0)
	)
	(junction
		(at 260.35 39.37)
		(diameter 0)
		(color 0 0 0 0)
	)
	(junction
		(at 322.58 173.99)
		(diameter 0)
		(color 0 0 0 0)
	)
	(junction
		(at 27.94 21.59)
		(diameter 0)
		(color 0 0 0 0)
	)
	(junction
		(at 387.35 139.7)
		(diameter 0)
		(color 0 0 0 0)
	)
	(junction
		(at 43.18 172.72)
		(diameter 0)
		(color 0 0 0 0)
	)
	(junction
		(at 36.83 172.72)
		(diameter 0)
		(color 0 0 0 0)
	)
	(junction
		(at 153.67 39.37)
		(diameter 0)
		(color 0 0 0 0)
	)
	(junction
		(at 226.06 58.42)
		(diameter 0)
		(color 0 0 0 0)
	)
	(junction
		(at 74.93 278.13)
		(diameter 0)
		(color 0 0 0 0)
	)
	(junction
		(at 66.04 257.81)
		(diameter 0)
		(color 0 0 0 0)
	)
	(junction
		(at 388.62 116.84)
		(diameter 0)
		(color 0 0 0 0)
	)
	(junction
		(at 226.06 53.34)
		(diameter 0)
		(color 0 0 0 0)
	)
	(junction
		(at 133.35 273.05)
		(diameter 0)
		(color 0 0 0 0)
	)
	(junction
		(at 341.63 38.1)
		(diameter 0)
		(color 0 0 0 0)
	)
	(junction
		(at 177.8 207.01)
		(diameter 0)
		(color 0 0 0 0)
	)
	(junction
		(at 40.64 193.04)
		(diameter 0)
		(color 0 0 0 0)
	)
	(junction
		(at 208.28 198.12)
		(diameter 0)
		(color 0 0 0 0)
	)
	(junction
		(at 59.69 208.28)
		(diameter 0)
		(color 0 0 0 0)
	)
	(junction
		(at 35.56 229.87)
		(diameter 0)
		(color 0 0 0 0)
	)
	(junction
		(at 175.26 95.25)
		(diameter 0)
		(color 0 0 0 0)
	)
	(junction
		(at 110.49 229.87)
		(diameter 0)
		(color 0 0 0 0)
	)
	(junction
		(at 393.7 128.27)
		(diameter 0)
		(color 0 0 0 0)
	)
	(junction
		(at 58.42 257.81)
		(diameter 0)
		(color 0 0 0 0)
	)
	(junction
		(at 317.5 38.1)
		(diameter 0)
		(color 0 0 0 0)
	)
	(junction
		(at 251.46 55.88)
		(diameter 0)
		(color 0 0 0 0)
	)
	(junction
		(at 93.98 172.72)
		(diameter 0)
		(color 0 0 0 0)
	)
	(junction
		(at 334.01 129.54)
		(diameter 0)
		(color 0 0 0 0)
	)
	(junction
		(at 55.88 205.74)
		(diameter 0)
		(color 0 0 0 0)
	)
	(junction
		(at 341.63 129.54)
		(diameter 0)
		(color 0 0 0 0)
	)
	(junction
		(at 116.84 214.63)
		(diameter 0)
		(color 0 0 0 0)
	)
	(junction
		(at 266.7 34.29)
		(diameter 0)
		(color 0 0 0 0)
	)
	(junction
		(at 254 53.34)
		(diameter 0)
		(color 0 0 0 0)
	)
	(junction
		(at 309.88 38.1)
		(diameter 0)
		(color 0 0 0 0)
	)
	(junction
		(at 386.08 24.13)
		(diameter 0)
		(color 0 0 0 0)
	)
	(junction
		(at 349.25 129.54)
		(diameter 0)
		(color 0 0 0 0)
	)
	(junction
		(at 53.34 172.72)
		(diameter 0)
		(color 0 0 0 0)
	)
	(junction
		(at 93.98 182.88)
		(diameter 0)
		(color 0 0 0 0)
	)
	(junction
		(at 74.93 229.87)
		(diameter 0)
		(color 0 0 0 0)
	)
	(junction
		(at 349.25 38.1)
		(diameter 0)
		(color 0 0 0 0)
	)
	(junction
		(at 134.62 95.25)
		(diameter 0)
		(color 0 0 0 0)
	)
	(junction
		(at 46.99 243.84)
		(diameter 0)
		(color 0 0 0 0)
	)
	(junction
		(at 27.94 229.87)
		(diameter 0)
		(color 0 0 0 0)
	)
	(junction
		(at 160.02 125.73)
		(diameter 0)
		(color 0 0 0 0)
	)
	(junction
		(at 46.99 198.12)
		(diameter 0)
		(color 0 0 0 0)
	)
	(junction
		(at 226.06 60.96)
		(diameter 0)
		(color 0 0 0 0)
	)
	(junction
		(at 393.7 116.84)
		(diameter 0)
		(color 0 0 0 0)
	)
	(junction
		(at 147.32 54.61)
		(diameter 0)
		(color 0 0 0 0)
	)
	(junction
		(at 167.64 54.61)
		(diameter 0)
		(color 0 0 0 0)
	)
	(junction
		(at 121.92 172.72)
		(diameter 0)
		(color 0 0 0 0)
	)
	(junction
		(at 334.01 38.1)
		(diameter 0)
		(color 0 0 0 0)
	)
	(junction
		(at 137.16 229.87)
		(diameter 0)
		(color 0 0 0 0)
	)
	(junction
		(at 326.39 129.54)
		(diameter 0)
		(color 0 0 0 0)
	)
	(junction
		(at 393.7 24.13)
		(diameter 0)
		(color 0 0 0 0)
	)
	(junction
		(at 118.11 229.87)
		(diameter 0)
		(color 0 0 0 0)
	)
	(junction
		(at 226.06 55.88)
		(diameter 0)
		(color 0 0 0 0)
	)
	(junction
		(at 147.32 25.4)
		(diameter 0)
		(color 0 0 0 0)
	)
	(junction
		(at 177.8 158.75)
		(diameter 0)
		(color 0 0 0 0)
	)
	(junction
		(at 147.32 39.37)
		(diameter 0)
		(color 0 0 0 0)
	)
	(junction
		(at 175.26 39.37)
		(diameter 0)
		(color 0 0 0 0)
	)
	(junction
		(at 393.7 38.1)
		(diameter 0)
		(color 0 0 0 0)
	)
	(junction
		(at 226.06 63.5)
		(diameter 0)
		(color 0 0 0 0)
	)
	(junction
		(at 121.92 265.43)
		(diameter 0)
		(color 0 0 0 0)
	)
	(junction
		(at 388.62 24.13)
		(diameter 0)
		(color 0 0 0 0)
	)
	(junction
		(at 125.73 229.87)
		(diameter 0)
		(color 0 0 0 0)
	)
	(junction
		(at 34.29 21.59)
		(diameter 0)
		(color 0 0 0 0)
	)
	(junction
		(at 156.21 25.4)
		(diameter 0)
		(color 0 0 0 0)
	)
	(junction
		(at 36.83 190.5)
		(diameter 0)
		(color 0 0 0 0)
	)
	(junction
		(at 140.97 278.13)
		(diameter 0)
		(color 0 0 0 0)
	)
	(junction
		(at 153.67 82.55)
		(diameter 0)
		(color 0 0 0 0)
	)
	(junction
		(at 43.18 195.58)
		(diameter 0)
		(color 0 0 0 0)
	)
	(junction
		(at 58.42 229.87)
		(diameter 0)
		(color 0 0 0 0)
	)
	(junction
		(at 110.49 257.81)
		(diameter 0)
		(color 0 0 0 0)
	)
	(junction
		(at 27.94 36.83)
		(diameter 0)
		(color 0 0 0 0)
	)
	(junction
		(at 66.04 243.84)
		(diameter 0)
		(color 0 0 0 0)
	)
	(junction
		(at 125.73 21.59)
		(diameter 0)
		(color 0 0 0 0)
	)
	(junction
		(at 167.64 21.59)
		(diameter 0)
		(color 0 0 0 0)
	)
	(junction
		(at 133.35 229.87)
		(diameter 0)
		(color 0 0 0 0)
	)
	(junction
		(at 106.68 255.27)
		(diameter 0)
		(color 0 0 0 0)
	)
	(no_connect
		(at 248.92 66.04)
	)
	(no_connect
		(at 212.09 120.65)
	)
	(no_connect
		(at 358.14 80.01)
	)
	(no_connect
		(at 64.77 85.09)
	)
	(no_connect
		(at 237.49 63.5)
	)
	(no_connect
		(at 212.09 49.53)
	)
	(no_connect
		(at 212.09 80.01)
	)
	(no_connect
		(at 358.14 68.58)
	)
	(no_connect
		(at 212.09 66.04)
	)
	(no_connect
		(at 358.14 160.02)
	)
	(no_connect
		(at 212.09 87.63)
	)
	(no_connect
		(at 64.77 90.17)
	)
	(no_connect
		(at 64.77 101.6)
	)
	(no_connect
		(at 212.09 90.17)
	)
	(no_connect
		(at 212.09 55.88)
	)
	(no_connect
		(at 184.15 106.68)
	)
	(no_connect
		(at 212.09 106.68)
	)
	(no_connect
		(at 212.09 82.55)
	)
	(no_connect
		(at 64.77 68.58)
	)
	(no_connect
		(at 358.14 60.96)
	)
	(no_connect
		(at 184.15 101.6)
	)
	(no_connect
		(at 358.14 66.04)
	)
	(no_connect
		(at 212.09 58.42)
	)
	(no_connect
		(at 212.09 41.91)
	)
	(no_connect
		(at 212.09 60.96)
	)
	(no_connect
		(at 212.09 71.12)
	)
	(no_connect
		(at 246.38 66.04)
	)
	(no_connect
		(at 64.77 58.42)
	)
	(no_connect
		(at 212.09 92.71)
	)
	(no_connect
		(at 212.09 114.3)
	)
	(no_connect
		(at 64.77 80.01)
	)
	(no_connect
		(at 64.77 87.63)
	)
	(no_connect
		(at 358.14 171.45)
	)
	(no_connect
		(at 212.09 118.11)
	)
	(no_connect
		(at 184.15 104.14)
	)
	(no_connect
		(at 212.09 99.06)
	)
	(no_connect
		(at 212.09 109.22)
	)
	(no_connect
		(at 212.09 53.34)
	)
	(no_connect
		(at 212.09 85.09)
	)
	(no_connect
		(at 64.77 60.96)
	)
	(no_connect
		(at 64.77 66.04)
	)
	(no_connect
		(at 212.09 68.58)
	)
	(no_connect
		(at 212.09 101.6)
	)
	(no_connect
		(at 64.77 63.5)
	)
	(no_connect
		(at 212.09 46.99)
	)
	(no_connect
		(at 358.14 152.4)
	)
	(no_connect
		(at 64.77 104.14)
	)
	(no_connect
		(at 212.09 63.5)
	)
	(no_connect
		(at 237.49 66.04)
	)
	(no_connect
		(at 212.09 111.76)
	)
	(no_connect
		(at 212.09 96.52)
	)
	(no_connect
		(at 64.77 71.12)
	)
	(no_connect
		(at 358.14 157.48)
	)
	(no_connect
		(at 64.77 82.55)
	)
	(no_connect
		(at 212.09 104.14)
	)
	(no_connect
		(at 64.77 92.71)
	)
	(wire
		(pts
			(xy 60.96 46.99) (xy 64.77 46.99)
		)
		(stroke
			(width 0)
			(type default)
		)
	)
	(wire
		(pts
			(xy 58.42 229.87) (xy 58.42 231.14)
		)
		(stroke
			(width 0)
			(type default)
		)
	)
	(wire
		(pts
			(xy 121.92 172.72) (xy 116.84 172.72)
		)
		(stroke
			(width 0)
			(type default)
		)
	)
	(wire
		(pts
			(xy 97.79 270.51) (xy 129.54 270.51)
		)
		(stroke
			(width 0)
			(type default)
		)
	)
	(wire
		(pts
			(xy 66.04 243.84) (xy 74.93 243.84)
		)
		(stroke
			(width 0)
			(type default)
		)
	)
	(wire
		(pts
			(xy 227.33 50.8) (xy 226.06 50.8)
		)
		(stroke
			(width 0)
			(type default)
		)
	)
	(wire
		(pts
			(xy 43.18 195.58) (xy 95.25 195.58)
		)
		(stroke
			(width 0)
			(type default)
		)
	)
	(wire
		(pts
			(xy 59.69 177.8) (xy 59.69 172.72)
		)
		(stroke
			(width 0)
			(type default)
		)
	)
	(wire
		(pts
			(xy 86.36 172.72) (xy 93.98 172.72)
		)
		(stroke
			(width 0)
			(type default)
		)
	)
	(wire
		(pts
			(xy 243.84 58.42) (xy 264.16 58.42)
		)
		(stroke
			(width 0)
			(type default)
		)
	)
	(wire
		(pts
			(xy 358.14 53.34) (xy 342.9 53.34)
		)
		(stroke
			(width 0)
			(type default)
		)
	)
	(wire
		(pts
			(xy 97.79 275.59) (xy 137.16 275.59)
		)
		(stroke
			(width 0)
			(type default)
		)
	)
	(wire
		(pts
			(xy 266.7 34.29) (xy 266.7 60.96)
		)
		(stroke
			(width 0)
			(type default)
		)
	)
	(wire
		(pts
			(xy 36.83 177.8) (xy 36.83 172.72)
		)
		(stroke
			(width 0)
			(type default)
		)
	)
	(wire
		(pts
			(xy 207.01 227.33) (xy 208.28 227.33)
		)
		(stroke
			(width 0)
			(type default)
		)
	)
	(wire
		(pts
			(xy 46.99 177.8) (xy 46.99 172.72)
		)
		(stroke
			(width 0)
			(type default)
		)
	)
	(wire
		(pts
			(xy 36.83 243.84) (xy 46.99 243.84)
		)
		(stroke
			(width 0)
			(type default)
		)
	)
	(wire
		(pts
			(xy 214.63 207.01) (xy 223.52 207.01)
		)
		(stroke
			(width 0)
			(type default)
		)
	)
	(wire
		(pts
			(xy 207.01 195.58) (xy 208.28 195.58)
		)
		(stroke
			(width 0)
			(type default)
		)
	)
	(wire
		(pts
			(xy 382.27 66.04) (xy 383.54 66.04)
		)
		(stroke
			(width 0)
			(type default)
		)
	)
	(wire
		(pts
			(xy 154.94 25.4) (xy 154.94 26.67)
		)
		(stroke
			(width 0)
			(type default)
		)
	)
	(wire
		(pts
			(xy 151.13 125.73) (xy 146.05 125.73)
		)
		(stroke
			(width 0)
			(type default)
		)
	)
	(wire
		(pts
			(xy 133.35 74.93) (xy 143.51 74.93)
		)
		(stroke
			(width 0)
			(type default)
		)
	)
	(wire
		(pts
			(xy 115.57 214.63) (xy 116.84 214.63)
		)
		(stroke
			(width 0)
			(type default)
		)
	)
	(wire
		(pts
			(xy 264.16 36.83) (xy 264.16 58.42)
		)
		(stroke
			(width 0)
			(type default)
		)
	)
	(wire
		(pts
			(xy 227.33 66.04) (xy 226.06 66.04)
		)
		(stroke
			(width 0)
			(type default)
		)
	)
	(wire
		(pts
			(xy 74.93 275.59) (xy 74.93 278.13)
		)
		(stroke
			(width 0)
			(type default)
		)
	)
	(wire
		(pts
			(xy 311.15 82.55) (xy 313.69 82.55)
		)
		(stroke
			(width 0)
			(type default)
		)
	)
	(wire
		(pts
			(xy 53.34 203.2) (xy 53.34 182.88)
		)
		(stroke
			(width 0)
			(type default)
		)
	)
	(wire
		(pts
			(xy 55.88 205.74) (xy 31.75 205.74)
		)
		(stroke
			(width 0)
			(type default)
		)
	)
	(wire
		(pts
			(xy 133.35 82.55) (xy 153.67 82.55)
		)
		(stroke
			(width 0)
			(type default)
		)
	)
	(wire
		(pts
			(xy 400.05 38.1) (xy 393.7 38.1)
		)
		(stroke
			(width 0)
			(type default)
		)
	)
	(wire
		(pts
			(xy 48.26 21.59) (xy 55.88 21.59)
		)
		(stroke
			(width 0)
			(type default)
		)
	)
	(wire
		(pts
			(xy 356.87 88.9) (xy 358.14 88.9)
		)
		(stroke
			(width 0)
			(type default)
		)
	)
	(wire
		(pts
			(xy 177.8 160.02) (xy 177.8 158.75)
		)
		(stroke
			(width 0)
			(type default)
		)
	)
	(wire
		(pts
			(xy 161.29 34.29) (xy 184.15 34.29)
		)
		(stroke
			(width 0)
			(type default)
		)
	)
	(wire
		(pts
			(xy 212.09 44.45) (xy 215.9 44.45)
		)
		(stroke
			(width 0)
			(type default)
		)
	)
	(wire
		(pts
			(xy 110.49 229.87) (xy 110.49 237.49)
		)
		(stroke
			(width 0)
			(type default)
		)
	)
	(wire
		(pts
			(xy 313.69 82.55) (xy 313.69 85.09)
		)
		(stroke
			(width 0)
			(type default)
		)
	)
	(wire
		(pts
			(xy 147.32 39.37) (xy 153.67 39.37)
		)
		(stroke
			(width 0)
			(type default)
		)
	)
	(wire
		(pts
			(xy 186.69 191.77) (xy 187.96 191.77)
		)
		(stroke
			(width 0)
			(type default)
		)
	)
	(wire
		(pts
			(xy 114.3 260.35) (xy 147.32 260.35)
		)
		(stroke
			(width 0)
			(type default)
		)
	)
	(wire
		(pts
			(xy 58.42 229.87) (xy 66.04 229.87)
		)
		(stroke
			(width 0)
			(type default)
		)
	)
	(wire
		(pts
			(xy 182.88 31.75) (xy 182.88 21.59)
		)
		(stroke
			(width 0)
			(type default)
		)
	)
	(wire
		(pts
			(xy 137.16 229.87) (xy 140.97 229.87)
		)
		(stroke
			(width 0)
			(type default)
		)
	)
	(wire
		(pts
			(xy 223.52 207.01) (xy 223.52 208.28)
		)
		(stroke
			(width 0)
			(type default)
		)
	)
	(wire
		(pts
			(xy 182.88 39.37) (xy 184.15 39.37)
		)
		(stroke
			(width 0)
			(type default)
		)
	)
	(wire
		(pts
			(xy 55.88 21.59) (xy 63.5 21.59)
		)
		(stroke
			(width 0)
			(type default)
		)
	)
	(wire
		(pts
			(xy 266.7 88.9) (xy 275.59 88.9)
		)
		(stroke
			(width 0)
			(type default)
		)
	)
	(wire
		(pts
			(xy 383.54 24.13) (xy 383.54 45.72)
		)
		(stroke
			(width 0)
			(type default)
		)
	)
	(wire
		(pts
			(xy 31.75 172.72) (xy 36.83 172.72)
		)
		(stroke
			(width 0)
			(type default)
		)
	)
	(wire
		(pts
			(xy 133.35 92.71) (xy 134.62 92.71)
		)
		(stroke
			(width 0)
			(type default)
		)
	)
	(wire
		(pts
			(xy 334.01 38.1) (xy 341.63 38.1)
		)
		(stroke
			(width 0)
			(type default)
		)
	)
	(wire
		(pts
			(xy 208.28 186.69) (xy 207.01 186.69)
		)
		(stroke
			(width 0)
			(type default)
		)
	)
	(wire
		(pts
			(xy 115.57 212.09) (xy 116.84 212.09)
		)
		(stroke
			(width 0)
			(type default)
		)
	)
	(wire
		(pts
			(xy 234.95 39.37) (xy 260.35 39.37)
		)
		(stroke
			(width 0)
			(type default)
		)
	)
	(wire
		(pts
			(xy 349.25 129.54) (xy 356.87 129.54)
		)
		(stroke
			(width 0)
			(type default)
		)
	)
	(wire
		(pts
			(xy 382.27 170.18) (xy 383.54 170.18)
		)
		(stroke
			(width 0)
			(type default)
		)
	)
	(wire
		(pts
			(xy 31.75 198.12) (xy 46.99 198.12)
		)
		(stroke
			(width 0)
			(type default)
		)
	)
	(wire
		(pts
			(xy 22.86 229.87) (xy 27.94 229.87)
		)
		(stroke
			(width 0)
			(type default)
		)
	)
	(wire
		(pts
			(xy 177.8 207.01) (xy 177.8 209.55)
		)
		(stroke
			(width 0)
			(type default)
		)
	)
	(wire
		(pts
			(xy 322.58 173.99) (xy 323.85 173.99)
		)
		(stroke
			(width 0)
			(type default)
		)
	)
	(wire
		(pts
			(xy 146.05 125.73) (xy 146.05 127)
		)
		(stroke
			(width 0)
			(type default)
		)
	)
	(wire
		(pts
			(xy 309.88 129.54) (xy 309.88 130.81)
		)
		(stroke
			(width 0)
			(type default)
		)
	)
	(wire
		(pts
			(xy 27.94 21.59) (xy 34.29 21.59)
		)
		(stroke
			(width 0)
			(type default)
		)
	)
	(wire
		(pts
			(xy 167.64 54.61) (xy 167.64 57.15)
		)
		(stroke
			(width 0)
			(type default)
		)
	)
	(wire
		(pts
			(xy 110.49 257.81) (xy 147.32 257.81)
		)
		(stroke
			(width 0)
			(type default)
		)
	)
	(wire
		(pts
			(xy 382.27 63.5) (xy 383.54 63.5)
		)
		(stroke
			(width 0)
			(type default)
		)
	)
	(wire
		(pts
			(xy 212.09 31.75) (xy 229.87 31.75)
		)
		(stroke
			(width 0)
			(type default)
		)
	)
	(wire
		(pts
			(xy 137.16 275.59) (xy 147.32 275.59)
		)
		(stroke
			(width 0)
			(type default)
		)
	)
	(wire
		(pts
			(xy 116.84 172.72) (xy 116.84 182.88)
		)
		(stroke
			(width 0)
			(type default)
		)
	)
	(wire
		(pts
			(xy 97.79 273.05) (xy 133.35 273.05)
		)
		(stroke
			(width 0)
			(type default)
		)
	)
	(wire
		(pts
			(xy 386.08 116.84) (xy 386.08 118.11)
		)
		(stroke
			(width 0)
			(type default)
		)
	)
	(wire
		(pts
			(xy 41.91 21.59) (xy 41.91 22.86)
		)
		(stroke
			(width 0)
			(type default)
		)
	)
	(wire
		(pts
			(xy 388.62 48.26) (xy 388.62 38.1)
		)
		(stroke
			(width 0)
			(type default)
		)
	)
	(wire
		(pts
			(xy 326.39 38.1) (xy 326.39 39.37)
		)
		(stroke
			(width 0)
			(type default)
		)
	)
	(wire
		(pts
			(xy 125.73 242.57) (xy 125.73 267.97)
		)
		(stroke
			(width 0)
			(type default)
		)
	)
	(wire
		(pts
			(xy 382.27 71.12) (xy 383.54 71.12)
		)
		(stroke
			(width 0)
			(type default)
		)
	)
	(wire
		(pts
			(xy 133.35 229.87) (xy 129.54 229.87)
		)
		(stroke
			(width 0)
			(type default)
		)
	)
	(wire
		(pts
			(xy 342.9 63.5) (xy 347.98 63.5)
		)
		(stroke
			(width 0)
			(type default)
		)
	)
	(wire
		(pts
			(xy 193.04 262.89) (xy 194.31 262.89)
		)
		(stroke
			(width 0)
			(type default)
		)
	)
	(wire
		(pts
			(xy 349.25 137.16) (xy 349.25 139.7)
		)
		(stroke
			(width 0)
			(type default)
		)
	)
	(wire
		(pts
			(xy 214.63 158.75) (xy 223.52 158.75)
		)
		(stroke
			(width 0)
			(type default)
		)
	)
	(wire
		(pts
			(xy 140.97 242.57) (xy 140.97 278.13)
		)
		(stroke
			(width 0)
			(type default)
		)
	)
	(wire
		(pts
			(xy 223.52 158.75) (xy 231.14 158.75)
		)
		(stroke
			(width 0)
			(type default)
		)
	)
	(wire
		(pts
			(xy 63.5 36.83) (xy 63.5 44.45)
		)
		(stroke
			(width 0)
			(type default)
		)
	)
	(wire
		(pts
			(xy 43.18 229.87) (xy 50.8 229.87)
		)
		(stroke
			(width 0)
			(type default)
		)
	)
	(wire
		(pts
			(xy 95.25 182.88) (xy 93.98 182.88)
		)
		(stroke
			(width 0)
			(type default)
		)
	)
	(wire
		(pts
			(xy 153.67 39.37) (xy 153.67 40.64)
		)
		(stroke
			(width 0)
			(type default)
		)
	)
	(wire
		(pts
			(xy 106.68 237.49) (xy 106.68 229.87)
		)
		(stroke
			(width 0)
			(type default)
		)
	)
	(wire
		(pts
			(xy 186.69 179.07) (xy 187.96 179.07)
		)
		(stroke
			(width 0)
			(type default)
		)
	)
	(wire
		(pts
			(xy 388.62 24.13) (xy 393.7 24.13)
		)
		(stroke
			(width 0)
			(type default)
		)
	)
	(wire
		(pts
			(xy 114.3 229.87) (xy 110.49 229.87)
		)
		(stroke
			(width 0)
			(type default)
		)
	)
	(wire
		(pts
			(xy 256.54 64.77) (xy 261.62 64.77)
		)
		(stroke
			(width 0)
			(type default)
		)
	)
	(wire
		(pts
			(xy 382.27 167.64) (xy 383.54 167.64)
		)
		(stroke
			(width 0)
			(type default)
		)
	)
	(wire
		(pts
			(xy 59.69 208.28) (xy 31.75 208.28)
		)
		(stroke
			(width 0)
			(type default)
		)
	)
	(wire
		(pts
			(xy 106.68 242.57) (xy 106.68 255.27)
		)
		(stroke
			(width 0)
			(type default)
		)
	)
	(wire
		(pts
			(xy 34.29 36.83) (xy 41.91 36.83)
		)
		(stroke
			(width 0)
			(type default)
		)
	)
	(wire
		(pts
			(xy 97.79 262.89) (xy 118.11 262.89)
		)
		(stroke
			(width 0)
			(type default)
		)
	)
	(wire
		(pts
			(xy 234.95 31.75) (xy 261.62 31.75)
		)
		(stroke
			(width 0)
			(type default)
		)
	)
	(wire
		(pts
			(xy 53.34 172.72) (xy 49.53 172.72)
		)
		(stroke
			(width 0)
			(type default)
		)
	)
	(wire
		(pts
			(xy 97.79 260.35) (xy 114.3 260.35)
		)
		(stroke
			(width 0)
			(type default)
		)
	)
	(wire
		(pts
			(xy 193.04 265.43) (xy 194.31 265.43)
		)
		(stroke
			(width 0)
			(type default)
		)
	)
	(wire
		(pts
			(xy 93.98 185.42) (xy 93.98 182.88)
		)
		(stroke
			(width 0)
			(type default)
		)
	)
	(wire
		(pts
			(xy 97.79 265.43) (xy 121.92 265.43)
		)
		(stroke
			(width 0)
			(type default)
		)
	)
	(wire
		(pts
			(xy 74.93 243.84) (xy 74.93 252.73)
		)
		(stroke
			(width 0)
			(type default)
		)
	)
	(wire
		(pts
			(xy 27.94 229.87) (xy 35.56 229.87)
		)
		(stroke
			(width 0)
			(type default)
		)
	)
	(wire
		(pts
			(xy 356.87 180.34) (xy 356.87 181.61)
		)
		(stroke
			(width 0)
			(type default)
		)
	)
	(wire
		(pts
			(xy 223.52 207.01) (xy 231.14 207.01)
		)
		(stroke
			(width 0)
			(type default)
		)
	)
	(wire
		(pts
			(xy 254 53.34) (xy 254 66.04)
		)
		(stroke
			(width 0)
			(type default)
		)
	)
	(wire
		(pts
			(xy 27.94 243.84) (xy 36.83 243.84)
		)
		(stroke
			(width 0)
			(type default)
		)
	)
	(wire
		(pts
			(xy 208.28 184.15) (xy 207.01 184.15)
		)
		(stroke
			(width 0)
			(type default)
		)
	)
	(wire
		(pts
			(xy 356.87 38.1) (xy 356.87 45.72)
		)
		(stroke
			(width 0)
			(type default)
		)
	)
	(wire
		(pts
			(xy 182.88 128.27) (xy 182.88 132.08)
		)
		(stroke
			(width 0)
			(type default)
		)
	)
	(wire
		(pts
			(xy 97.79 257.81) (xy 110.49 257.81)
		)
		(stroke
			(width 0)
			(type default)
		)
	)
	(wire
		(pts
			(xy 388.62 115.57) (xy 388.62 116.84)
		)
		(stroke
			(width 0)
			(type default)
		)
	)
	(wire
		(pts
			(xy 74.93 275.59) (xy 77.47 275.59)
		)
		(stroke
			(width 0)
			(type default)
		)
	)
	(wire
		(pts
			(xy 341.63 38.1) (xy 341.63 39.37)
		)
		(stroke
			(width 0)
			(type default)
		)
	)
	(wire
		(pts
			(xy 184.15 217.17) (xy 184.15 207.01)
		)
		(stroke
			(width 0)
			(type default)
		)
	)
	(wire
		(pts
			(xy 217.17 86.36) (xy 217.17 74.93)
		)
		(stroke
			(width 0)
			(type default)
		)
	)
	(wire
		(pts
			(xy 326.39 38.1) (xy 317.5 38.1)
		)
		(stroke
			(width 0)
			(type default)
		)
	)
	(wire
		(pts
			(xy 49.53 177.8) (xy 49.53 172.72)
		)
		(stroke
			(width 0)
			(type default)
		)
	)
	(wire
		(pts
			(xy 116.84 212.09) (xy 116.84 214.63)
		)
		(stroke
			(width 0)
			(type default)
		)
	)
	(wire
		(pts
			(xy 186.69 176.53) (xy 187.96 176.53)
		)
		(stroke
			(width 0)
			(type default)
		)
	)
	(wire
		(pts
			(xy 147.32 54.61) (xy 147.32 57.15)
		)
		(stroke
			(width 0)
			(type default)
		)
	)
	(wire
		(pts
			(xy 208.28 227.33) (xy 208.28 228.6)
		)
		(stroke
			(width 0)
			(type default)
		)
	)
	(wire
		(pts
			(xy 93.98 172.72) (xy 93.98 182.88)
		)
		(stroke
			(width 0)
			(type default)
		)
	)
	(wire
		(pts
			(xy 382.27 162.56) (xy 383.54 162.56)
		)
		(stroke
			(width 0)
			(type default)
		)
	)
	(wire
		(pts
			(xy 260.35 39.37) (xy 260.35 53.34)
		)
		(stroke
			(width 0)
			(type default)
		)
	)
	(wire
		(pts
			(xy 386.08 24.13) (xy 388.62 24.13)
		)
		(stroke
			(width 0)
			(type default)
		)
	)
	(wire
		(pts
			(xy 116.84 214.63) (xy 116.84 215.9)
		)
		(stroke
			(width 0)
			(type default)
		)
	)
	(wire
		(pts
			(xy 266.7 34.29) (xy 275.59 34.29)
		)
		(stroke
			(width 0)
			(type default)
		)
	)
	(wire
		(pts
			(xy 137.16 237.49) (xy 137.16 229.87)
		)
		(stroke
			(width 0)
			(type default)
		)
	)
	(wire
		(pts
			(xy 115.57 198.12) (xy 123.19 198.12)
		)
		(stroke
			(width 0)
			(type default)
		)
	)
	(wire
		(pts
			(xy 207.01 219.71) (xy 223.52 219.71)
		)
		(stroke
			(width 0)
			(type default)
		)
	)
	(wire
		(pts
			(xy 27.94 21.59) (xy 27.94 22.86)
		)
		(stroke
			(width 0)
			(type default)
		)
	)
	(wire
		(pts
			(xy 387.35 140.97) (xy 387.35 139.7)
		)
		(stroke
			(width 0)
			(type default)
		)
	)
	(wire
		(pts
			(xy 383.54 116.84) (xy 386.08 116.84)
		)
		(stroke
			(width 0)
			(type default)
		)
	)
	(wire
		(pts
			(xy 34.29 21.59) (xy 34.29 22.86)
		)
		(stroke
			(width 0)
			(type default)
		)
	)
	(wire
		(pts
			(xy 48.26 77.47) (xy 64.77 77.47)
		)
		(stroke
			(width 0)
			(type default)
		)
	)
	(wire
		(pts
			(xy 322.58 87.63) (xy 323.85 87.63)
		)
		(stroke
			(width 0)
			(type default)
		)
	)
	(wire
		(pts
			(xy 133.35 80.01) (xy 151.13 80.01)
		)
		(stroke
			(width 0)
			(type default)
		)
	)
	(wire
		(pts
			(xy 326.39 38.1) (xy 334.01 38.1)
		)
		(stroke
			(width 0)
			(type default)
		)
	)
	(wire
		(pts
			(xy 129.54 242.57) (xy 129.54 270.51)
		)
		(stroke
			(width 0)
			(type default)
		)
	)
	(wire
		(pts
			(xy 237.49 55.88) (xy 251.46 55.88)
		)
		(stroke
			(width 0)
			(type default)
		)
	)
	(wire
		(pts
			(xy 118.11 229.87) (xy 118.11 237.49)
		)
		(stroke
			(width 0)
			(type default)
		)
	)
	(wire
		(pts
			(xy 400.05 128.27) (xy 393.7 128.27)
		)
		(stroke
			(width 0)
			(type default)
		)
	)
	(wire
		(pts
			(xy 237.49 50.8) (xy 241.3 50.8)
		)
		(stroke
			(width 0)
			(type default)
		)
	)
	(wire
		(pts
			(xy 382.27 45.72) (xy 383.54 45.72)
		)
		(stroke
			(width 0)
			(type default)
		)
	)
	(wire
		(pts
			(xy 55.88 177.8) (xy 55.88 172.72)
		)
		(stroke
			(width 0)
			(type default)
		)
	)
	(wire
		(pts
			(xy 95.25 185.42) (xy 93.98 185.42)
		)
		(stroke
			(width 0)
			(type default)
		)
	)
	(wire
		(pts
			(xy 388.62 139.7) (xy 388.62 128.27)
		)
		(stroke
			(width 0)
			(type default)
		)
	)
	(wire
		(pts
			(xy 175.26 21.59) (xy 175.26 22.86)
		)
		(stroke
			(width 0)
			(type default)
		)
	)
	(wire
		(pts
			(xy 121.92 242.57) (xy 121.92 265.43)
		)
		(stroke
			(width 0)
			(type default)
		)
	)
	(wire
		(pts
			(xy 386.08 116.84) (xy 388.62 116.84)
		)
		(stroke
			(width 0)
			(type default)
		)
	)
	(wire
		(pts
			(xy 215.9 88.9) (xy 261.62 88.9)
		)
		(stroke
			(width 0)
			(type default)
		)
	)
	(wire
		(pts
			(xy 334.01 129.54) (xy 334.01 130.81)
		)
		(stroke
			(width 0)
			(type default)
		)
	)
	(wire
		(pts
			(xy 181.61 21.59) (xy 182.88 21.59)
		)
		(stroke
			(width 0)
			(type default)
		)
	)
	(wire
		(pts
			(xy 86.36 172.72) (xy 86.36 173.99)
		)
		(stroke
			(width 0)
			(type default)
		)
	)
	(wire
		(pts
			(xy 382.27 177.8) (xy 383.54 177.8)
		)
		(stroke
			(width 0)
			(type default)
		)
	)
	(wire
		(pts
			(xy 140.97 278.13) (xy 147.32 278.13)
		)
		(stroke
			(width 0)
			(type default)
		)
	)
	(wire
		(pts
			(xy 400.05 38.1) (xy 400.05 39.37)
		)
		(stroke
			(width 0)
			(type default)
		)
	)
	(wire
		(pts
			(xy 97.79 252.73) (xy 99.06 252.73)
		)
		(stroke
			(width 0)
			(type default)
		)
	)
	(wire
		(pts
			(xy 186.69 186.69) (xy 187.96 186.69)
		)
		(stroke
			(width 0)
			(type default)
		)
	)
	(wire
		(pts
			(xy 182.88 59.69) (xy 182.88 54.61)
		)
		(stroke
			(width 0)
			(type default)
		)
	)
	(wire
		(pts
			(xy 50.8 229.87) (xy 58.42 229.87)
		)
		(stroke
			(width 0)
			(type default)
		)
	)
	(wire
		(pts
			(xy 227.33 58.42) (xy 226.06 58.42)
		)
		(stroke
			(width 0)
			(type default)
		)
	)
	(wire
		(pts
			(xy 261.62 31.75) (xy 275.59 31.75)
		)
		(stroke
			(width 0)
			(type default)
		)
	)
	(wire
		(pts
			(xy 53.34 172.72) (xy 55.88 172.72)
		)
		(stroke
			(width 0)
			(type default)
		)
	)
	(wire
		(pts
			(xy 114.3 242.57) (xy 114.3 260.35)
		)
		(stroke
			(width 0)
			(type default)
		)
	)
	(wire
		(pts
			(xy 212.09 39.37) (xy 229.87 39.37)
		)
		(stroke
			(width 0)
			(type default)
		)
	)
	(wire
		(pts
			(xy 207.01 217.17) (xy 210.82 217.17)
		)
		(stroke
			(width 0)
			(type default)
		)
	)
	(wire
		(pts
			(xy 382.27 60.96) (xy 383.54 60.96)
		)
		(stroke
			(width 0)
			(type default)
		)
	)
	(wire
		(pts
			(xy 208.28 198.12) (xy 208.28 199.39)
		)
		(stroke
			(width 0)
			(type default)
		)
	)
	(wire
		(pts
			(xy 210.82 158.75) (xy 214.63 158.75)
		)
		(stroke
			(width 0)
			(type default)
		)
	)
	(wire
		(pts
			(xy 125.73 267.97) (xy 147.32 267.97)
		)
		(stroke
			(width 0)
			(type default)
		)
	)
	(wire
		(pts
			(xy 153.67 82.55) (xy 184.15 82.55)
		)
		(stroke
			(width 0)
			(type default)
		)
	)
	(wire
		(pts
			(xy 326.39 129.54) (xy 334.01 129.54)
		)
		(stroke
			(width 0)
			(type default)
		)
	)
	(wire
		(pts
			(xy 322.58 176.53) (xy 322.58 173.99)
		)
		(stroke
			(width 0)
			(type default)
		)
	)
	(wire
		(pts
			(xy 311.15 173.99) (xy 313.69 173.99)
		)
		(stroke
			(width 0)
			(type default)
		)
	)
	(wire
		(pts
			(xy 349.25 48.26) (xy 358.14 48.26)
		)
		(stroke
			(width 0)
			(type default)
		)
	)
	(wire
		(pts
			(xy 137.16 229.87) (xy 133.35 229.87)
		)
		(stroke
			(width 0)
			(type default)
		)
	)
	(wire
		(pts
			(xy 73.66 172.72) (xy 77.47 172.72)
		)
		(stroke
			(width 0)
			(type default)
		)
	)
	(wire
		(pts
			(xy 382.27 76.2) (xy 383.54 76.2)
		)
		(stroke
			(width 0)
			(type default)
		)
	)
	(wire
		(pts
			(xy 127 172.72) (xy 121.92 172.72)
		)
		(stroke
			(width 0)
			(type default)
		)
	)
	(wire
		(pts
			(xy 184.15 207.01) (xy 177.8 207.01)
		)
		(stroke
			(width 0)
			(type default)
		)
	)
	(wire
		(pts
			(xy 64.77 99.06) (xy 54.61 99.06)
		)
		(stroke
			(width 0)
			(type default)
		)
	)
	(wire
		(pts
			(xy 382.27 137.16) (xy 383.54 137.16)
		)
		(stroke
			(width 0)
			(type default)
		)
	)
	(wire
		(pts
			(xy 382.27 147.32) (xy 383.54 147.32)
		)
		(stroke
			(width 0)
			(type default)
		)
	)
	(wire
		(pts
			(xy 27.94 36.83) (xy 25.4 36.83)
		)
		(stroke
			(width 0)
			(type default)
		)
	)
	(wire
		(pts
			(xy 313.69 173.99) (xy 313.69 176.53)
		)
		(stroke
			(width 0)
			(type default)
		)
	)
	(wire
		(pts
			(xy 382.27 81.28) (xy 383.54 81.28)
		)
		(stroke
			(width 0)
			(type default)
		)
	)
	(wire
		(pts
			(xy 52.07 49.53) (xy 64.77 49.53)
		)
		(stroke
			(width 0)
			(type default)
		)
	)
	(wire
		(pts
			(xy 129.54 229.87) (xy 125.73 229.87)
		)
		(stroke
			(width 0)
			(type default)
		)
	)
	(wire
		(pts
			(xy 187.96 167.64) (xy 184.15 167.64)
		)
		(stroke
			(width 0)
			(type default)
		)
	)
	(wire
		(pts
			(xy 251.46 55.88) (xy 261.62 55.88)
		)
		(stroke
			(width 0)
			(type default)
		)
	)
	(wire
		(pts
			(xy 130.81 21.59) (xy 130.81 25.4)
		)
		(stroke
			(width 0)
			(type default)
		)
	)
	(wire
		(pts
			(xy 393.7 24.13) (xy 393.7 25.4)
		)
		(stroke
			(width 0)
			(type default)
		)
	)
	(wire
		(pts
			(xy 317.5 129.54) (xy 309.88 129.54)
		)
		(stroke
			(width 0)
			(type default)
		)
	)
	(wire
		(pts
			(xy 167.64 39.37) (xy 167.64 40.64)
		)
		(stroke
			(width 0)
			(type default)
		)
	)
	(wire
		(pts
			(xy 41.91 21.59) (xy 48.26 21.59)
		)
		(stroke
			(width 0)
			(type default)
		)
	)
	(wire
		(pts
			(xy 353.06 86.36) (xy 358.14 86.36)
		)
		(stroke
			(width 0)
			(type default)
		)
	)
	(wire
		(pts
			(xy 154.94 130.81) (xy 154.94 132.08)
		)
		(stroke
			(width 0)
			(type default)
		)
	)
	(wire
		(pts
			(xy 34.29 36.83) (xy 34.29 38.1)
		)
		(stroke
			(width 0)
			(type default)
		)
	)
	(wire
		(pts
			(xy 226.06 63.5) (xy 227.33 63.5)
		)
		(stroke
			(width 0)
			(type default)
		)
	)
	(wire
		(pts
			(xy 182.88 128.27) (xy 184.15 128.27)
		)
		(stroke
			(width 0)
			(type default)
		)
	)
	(wire
		(pts
			(xy 125.73 229.87) (xy 125.73 237.49)
		)
		(stroke
			(width 0)
			(type default)
		)
	)
	(wire
		(pts
			(xy 115.57 205.74) (xy 123.19 205.74)
		)
		(stroke
			(width 0)
			(type default)
		)
	)
	(wire
		(pts
			(xy 322.58 87.63) (xy 322.58 90.17)
		)
		(stroke
			(width 0)
			(type default)
		)
	)
	(wire
		(pts
			(xy 309.88 38.1) (xy 309.88 39.37)
		)
		(stroke
			(width 0)
			(type default)
		)
	)
	(wire
		(pts
			(xy 147.32 25.4) (xy 147.32 26.67)
		)
		(stroke
			(width 0)
			(type default)
		)
	)
	(wire
		(pts
			(xy 46.99 243.84) (xy 57.15 243.84)
		)
		(stroke
			(width 0)
			(type default)
		)
	)
	(wire
		(pts
			(xy 208.28 191.77) (xy 207.01 191.77)
		)
		(stroke
			(width 0)
			(type default)
		)
	)
	(wire
		(pts
			(xy 313.69 82.55) (xy 322.58 82.55)
		)
		(stroke
			(width 0)
			(type default)
		)
	)
	(wire
		(pts
			(xy 349.25 139.7) (xy 358.14 139.7)
		)
		(stroke
			(width 0)
			(type default)
		)
	)
	(wire
		(pts
			(xy 226.06 53.34) (xy 226.06 55.88)
		)
		(stroke
			(width 0)
			(type default)
		)
	)
	(wire
		(pts
			(xy 161.29 39.37) (xy 161.29 40.64)
		)
		(stroke
			(width 0)
			(type default)
		)
	)
	(wire
		(pts
			(xy 156.21 25.4) (xy 161.29 25.4)
		)
		(stroke
			(width 0)
			(type default)
		)
	)
	(wire
		(pts
			(xy 256.54 66.04) (xy 256.54 64.77)
		)
		(stroke
			(width 0)
			(type default)
		)
	)
	(wire
		(pts
			(xy 50.8 229.87) (xy 50.8 231.14)
		)
		(stroke
			(width 0)
			(type default)
		)
	)
	(wire
		(pts
			(xy 266.7 86.36) (xy 275.59 86.36)
		)
		(stroke
			(width 0)
			(type default)
		)
	)
	(wire
		(pts
			(xy 74.93 229.87) (xy 106.68 229.87)
		)
		(stroke
			(width 0)
			(type default)
		)
	)
	(wire
		(pts
			(xy 182.88 44.45) (xy 182.88 39.37)
		)
		(stroke
			(width 0)
			(type default)
		)
	)
	(wire
		(pts
			(xy 306.07 129.54) (xy 309.88 129.54)
		)
		(stroke
			(width 0)
			(type default)
		)
	)
	(wire
		(pts
			(xy 143.51 21.59) (xy 167.64 21.59)
		)
		(stroke
			(width 0)
			(type default)
		)
	)
	(wire
		(pts
			(xy 36.83 172.72) (xy 40.64 172.72)
		)
		(stroke
			(width 0)
			(type default)
		)
	)
	(wire
		(pts
			(xy 313.69 173.99) (xy 322.58 173.99)
		)
		(stroke
			(width 0)
			(type default)
		)
	)
	(wire
		(pts
			(xy 317.5 38.1) (xy 309.88 38.1)
		)
		(stroke
			(width 0)
			(type default)
		)
	)
	(wire
		(pts
			(xy 400.05 128.27) (xy 400.05 129.54)
		)
		(stroke
			(width 0)
			(type default)
		)
	)
	(wire
		(pts
			(xy 125.73 21.59) (xy 125.73 39.37)
		)
		(stroke
			(width 0)
			(type default)
		)
	)
	(wire
		(pts
			(xy 36.83 190.5) (xy 36.83 182.88)
		)
		(stroke
			(width 0)
			(type default)
		)
	)
	(wire
		(pts
			(xy 74.93 278.13) (xy 77.47 278.13)
		)
		(stroke
			(width 0)
			(type default)
		)
	)
	(wire
		(pts
			(xy 52.07 36.83) (xy 52.07 49.53)
		)
		(stroke
			(width 0)
			(type default)
		)
	)
	(wire
		(pts
			(xy 125.73 229.87) (xy 121.92 229.87)
		)
		(stroke
			(width 0)
			(type default)
		)
	)
	(wire
		(pts
			(xy 48.26 74.93) (xy 64.77 74.93)
		)
		(stroke
			(width 0)
			(type default)
		)
	)
	(wire
		(pts
			(xy 95.25 172.72) (xy 93.98 172.72)
		)
		(stroke
			(width 0)
			(type default)
		)
	)
	(wire
		(pts
			(xy 27.94 36.83) (xy 27.94 38.1)
		)
		(stroke
			(width 0)
			(type default)
		)
	)
	(wire
		(pts
			(xy 387.35 139.7) (xy 388.62 139.7)
		)
		(stroke
			(width 0)
			(type default)
		)
	)
	(wire
		(pts
			(xy 210.82 207.01) (xy 214.63 207.01)
		)
		(stroke
			(width 0)
			(type default)
		)
	)
	(wire
		(pts
			(xy 347.98 177.8) (xy 345.44 177.8)
		)
		(stroke
			(width 0)
			(type default)
		)
	)
	(wire
		(pts
			(xy 334.01 129.54) (xy 341.63 129.54)
		)
		(stroke
			(width 0)
			(type default)
		)
	)
	(wire
		(pts
			(xy 63.5 44.45) (xy 64.77 44.45)
		)
		(stroke
			(width 0)
			(type default)
		)
	)
	(wire
		(pts
			(xy 53.34 203.2) (xy 95.25 203.2)
		)
		(stroke
			(width 0)
			(type default)
		)
	)
	(wire
		(pts
			(xy 226.06 55.88) (xy 226.06 58.42)
		)
		(stroke
			(width 0)
			(type default)
		)
	)
	(wire
		(pts
			(xy 388.62 128.27) (xy 393.7 128.27)
		)
		(stroke
			(width 0)
			(type default)
		)
	)
	(wire
		(pts
			(xy 77.47 265.43) (xy 76.2 265.43)
		)
		(stroke
			(width 0)
			(type default)
		)
	)
	(wire
		(pts
			(xy 194.31 273.05) (xy 194.31 274.32)
		)
		(stroke
			(width 0)
			(type default)
		)
	)
	(wire
		(pts
			(xy 251.46 55.88) (xy 251.46 66.04)
		)
		(stroke
			(width 0)
			(type default)
		)
	)
	(wire
		(pts
			(xy 31.75 195.58) (xy 43.18 195.58)
		)
		(stroke
			(width 0)
			(type default)
		)
	)
	(wire
		(pts
			(xy 34.29 21.59) (xy 41.91 21.59)
		)
		(stroke
			(width 0)
			(type default)
		)
	)
	(wire
		(pts
			(xy 186.69 223.52) (xy 187.96 223.52)
		)
		(stroke
			(width 0)
			(type default)
		)
	)
	(wire
		(pts
			(xy 106.68 255.27) (xy 147.32 255.27)
		)
		(stroke
			(width 0)
			(type default)
		)
	)
	(wire
		(pts
			(xy 342.9 82.55) (xy 358.14 82.55)
		)
		(stroke
			(width 0)
			(type default)
		)
	)
	(wire
		(pts
			(xy 115.57 193.04) (xy 123.19 193.04)
		)
		(stroke
			(width 0)
			(type default)
		)
	)
	(wire
		(pts
			(xy 160.02 125.73) (xy 158.75 125.73)
		)
		(stroke
			(width 0)
			(type default)
		)
	)
	(wire
		(pts
			(xy 43.18 177.8) (xy 43.18 172.72)
		)
		(stroke
			(width 0)
			(type default)
		)
	)
	(wire
		(pts
			(xy 356.87 129.54) (xy 356.87 137.16)
		)
		(stroke
			(width 0)
			(type default)
		)
	)
	(wire
		(pts
			(xy 143.51 54.61) (xy 147.32 54.61)
		)
		(stroke
			(width 0)
			(type default)
		)
	)
	(wire
		(pts
			(xy 393.7 128.27) (xy 393.7 129.54)
		)
		(stroke
			(width 0)
			(type default)
		)
	)
	(wire
		(pts
			(xy 129.54 237.49) (xy 129.54 229.87)
		)
		(stroke
			(width 0)
			(type default)
		)
	)
	(wire
		(pts
			(xy 161.29 54.61) (xy 161.29 57.15)
		)
		(stroke
			(width 0)
			(type default)
		)
	)
	(wire
		(pts
			(xy 133.35 242.57) (xy 133.35 273.05)
		)
		(stroke
			(width 0)
			(type default)
		)
	)
	(wire
		(pts
			(xy 334.01 38.1) (xy 334.01 39.37)
		)
		(stroke
			(width 0)
			(type default)
		)
	)
	(wire
		(pts
			(xy 133.35 87.63) (xy 134.62 87.63)
		)
		(stroke
			(width 0)
			(type default)
		)
	)
	(wire
		(pts
			(xy 59.69 208.28) (xy 59.69 182.88)
		)
		(stroke
			(width 0)
			(type default)
		)
	)
	(wire
		(pts
			(xy 153.67 54.61) (xy 153.67 57.15)
		)
		(stroke
			(width 0)
			(type default)
		)
	)
	(wire
		(pts
			(xy 57.15 245.11) (xy 57.15 243.84)
		)
		(stroke
			(width 0)
			(type default)
		)
	)
	(wire
		(pts
			(xy 175.26 125.73) (xy 184.15 125.73)
		)
		(stroke
			(width 0)
			(type default)
		)
	)
	(wire
		(pts
			(xy 167.64 39.37) (xy 175.26 39.37)
		)
		(stroke
			(width 0)
			(type default)
		)
	)
	(wire
		(pts
			(xy 382.27 83.82) (xy 383.54 83.82)
		)
		(stroke
			(width 0)
			(type default)
		)
	)
	(wire
		(pts
			(xy 208.28 173.99) (xy 207.01 173.99)
		)
		(stroke
			(width 0)
			(type default)
		)
	)
	(wire
		(pts
			(xy 114.3 237.49) (xy 114.3 229.87)
		)
		(stroke
			(width 0)
			(type default)
		)
	)
	(wire
		(pts
			(xy 66.04 229.87) (xy 74.93 229.87)
		)
		(stroke
			(width 0)
			(type default)
		)
	)
	(wire
		(pts
			(xy 151.13 80.01) (xy 151.13 88.9)
		)
		(stroke
			(width 0)
			(type default)
		)
	)
	(wire
		(pts
			(xy 186.69 184.15) (xy 187.96 184.15)
		)
		(stroke
			(width 0)
			(type default)
		)
	)
	(wire
		(pts
			(xy 58.42 257.81) (xy 58.42 259.08)
		)
		(stroke
			(width 0)
			(type default)
		)
	)
	(wire
		(pts
			(xy 382.27 157.48) (xy 383.54 157.48)
		)
		(stroke
			(width 0)
			(type default)
		)
	)
	(wire
		(pts
			(xy 237.49 60.96) (xy 241.3 60.96)
		)
		(stroke
			(width 0)
			(type default)
		)
	)
	(wire
		(pts
			(xy 217.17 86.36) (xy 261.62 86.36)
		)
		(stroke
			(width 0)
			(type default)
		)
	)
	(wire
		(pts
			(xy 388.62 38.1) (xy 393.7 38.1)
		)
		(stroke
			(width 0)
			(type default)
		)
	)
	(wire
		(pts
			(xy 227.33 60.96) (xy 226.06 60.96)
		)
		(stroke
			(width 0)
			(type default)
		)
	)
	(wire
		(pts
			(xy 115.57 190.5) (xy 123.19 190.5)
		)
		(stroke
			(width 0)
			(type default)
		)
	)
	(wire
		(pts
			(xy 55.88 21.59) (xy 55.88 22.86)
		)
		(stroke
			(width 0)
			(type default)
		)
	)
	(wire
		(pts
			(xy 382.27 152.4) (xy 383.54 152.4)
		)
		(stroke
			(width 0)
			(type default)
		)
	)
	(wire
		(pts
			(xy 184.15 59.69) (xy 182.88 59.69)
		)
		(stroke
			(width 0)
			(type default)
		)
	)
	(wire
		(pts
			(xy 43.18 195.58) (xy 43.18 182.88)
		)
		(stroke
			(width 0)
			(type default)
		)
	)
	(wire
		(pts
			(xy 118.11 229.87) (xy 114.3 229.87)
		)
		(stroke
			(width 0)
			(type default)
		)
	)
	(wire
		(pts
			(xy 43.18 172.72) (xy 46.99 172.72)
		)
		(stroke
			(width 0)
			(type default)
		)
	)
	(wire
		(pts
			(xy 66.04 257.81) (xy 66.04 259.08)
		)
		(stroke
			(width 0)
			(type default)
		)
	)
	(wire
		(pts
			(xy 356.87 88.9) (xy 356.87 90.17)
		)
		(stroke
			(width 0)
			(type default)
		)
	)
	(wire
		(pts
			(xy 115.57 200.66) (xy 123.19 200.66)
		)
		(stroke
			(width 0)
			(type default)
		)
	)
	(wire
		(pts
			(xy 241.3 60.96) (xy 241.3 66.04)
		)
		(stroke
			(width 0)
			(type default)
		)
	)
	(wire
		(pts
			(xy 400.05 24.13) (xy 393.7 24.13)
		)
		(stroke
			(width 0)
			(type default)
		)
	)
	(wire
		(pts
			(xy 40.64 193.04) (xy 40.64 182.88)
		)
		(stroke
			(width 0)
			(type default)
		)
	)
	(wire
		(pts
			(xy 226.06 50.8) (xy 226.06 53.34)
		)
		(stroke
			(width 0)
			(type default)
		)
	)
	(wire
		(pts
			(xy 212.09 77.47) (xy 215.9 77.47)
		)
		(stroke
			(width 0)
			(type default)
		)
	)
	(wire
		(pts
			(xy 121.92 237.49) (xy 121.92 229.87)
		)
		(stroke
			(width 0)
			(type default)
		)
	)
	(wire
		(pts
			(xy 168.91 158.75) (xy 177.8 158.75)
		)
		(stroke
			(width 0)
			(type default)
		)
	)
	(wire
		(pts
			(xy 27.94 229.87) (xy 27.94 231.14)
		)
		(stroke
			(width 0)
			(type default)
		)
	)
	(wire
		(pts
			(xy 341.63 129.54) (xy 341.63 130.81)
		)
		(stroke
			(width 0)
			(type default)
		)
	)
	(wire
		(pts
			(xy 214.63 158.75) (xy 214.63 160.02)
		)
		(stroke
			(width 0)
			(type default)
		)
	)
	(wire
		(pts
			(xy 175.26 102.87) (xy 175.26 101.6)
		)
		(stroke
			(width 0)
			(type default)
		)
	)
	(wire
		(pts
			(xy 210.82 167.64) (xy 210.82 158.75)
		)
		(stroke
			(width 0)
			(type default)
		)
	)
	(wire
		(pts
			(xy 226.06 63.5) (xy 226.06 66.04)
		)
		(stroke
			(width 0)
			(type default)
		)
	)
	(wire
		(pts
			(xy 223.52 165.1) (xy 223.52 170.18)
		)
		(stroke
			(width 0)
			(type default)
		)
	)
	(wire
		(pts
			(xy 181.61 20.32) (xy 181.61 21.59)
		)
		(stroke
			(width 0)
			(type default)
		)
	)
	(wire
		(pts
			(xy 326.39 129.54) (xy 317.5 129.54)
		)
		(stroke
			(width 0)
			(type default)
		)
	)
	(wire
		(pts
			(xy 322.58 85.09) (xy 322.58 82.55)
		)
		(stroke
			(width 0)
			(type default)
		)
	)
	(wire
		(pts
			(xy 121.92 173.99) (xy 121.92 172.72)
		)
		(stroke
			(width 0)
			(type default)
		)
	)
	(wire
		(pts
			(xy 261.62 31.75) (xy 261.62 55.88)
		)
		(stroke
			(width 0)
			(type default)
		)
	)
	(wire
		(pts
			(xy 46.99 198.12) (xy 46.99 182.88)
		)
		(stroke
			(width 0)
			(type default)
		)
	)
	(wire
		(pts
			(xy 60.96 46.99) (xy 60.96 43.18)
		)
		(stroke
			(width 0)
			(type default)
		)
	)
	(wire
		(pts
			(xy 110.49 242.57) (xy 110.49 257.81)
		)
		(stroke
			(width 0)
			(type default)
		)
	)
	(wire
		(pts
			(xy 134.62 95.25) (xy 134.62 99.06)
		)
		(stroke
			(width 0)
			(type default)
		)
	)
	(wire
		(pts
			(xy 234.95 36.83) (xy 264.16 36.83)
		)
		(stroke
			(width 0)
			(type default)
		)
	)
	(wire
		(pts
			(xy 125.73 39.37) (xy 147.32 39.37)
		)
		(stroke
			(width 0)
			(type default)
		)
	)
	(wire
		(pts
			(xy 322.58 82.55) (xy 323.85 82.55)
		)
		(stroke
			(width 0)
			(type default)
		)
	)
	(wire
		(pts
			(xy 213.36 125.73) (xy 213.36 128.27)
		)
		(stroke
			(width 0)
			(type default)
		)
	)
	(wire
		(pts
			(xy 212.09 34.29) (xy 229.87 34.29)
		)
		(stroke
			(width 0)
			(type default)
		)
	)
	(wire
		(pts
			(xy 175.26 96.52) (xy 175.26 95.25)
		)
		(stroke
			(width 0)
			(type default)
		)
	)
	(wire
		(pts
			(xy 382.27 172.72) (xy 383.54 172.72)
		)
		(stroke
			(width 0)
			(type default)
		)
	)
	(wire
		(pts
			(xy 322.58 179.07) (xy 322.58 181.61)
		)
		(stroke
			(width 0)
			(type default)
		)
	)
	(wire
		(pts
			(xy 184.15 158.75) (xy 177.8 158.75)
		)
		(stroke
			(width 0)
			(type default)
		)
	)
	(wire
		(pts
			(xy 55.88 205.74) (xy 95.25 205.74)
		)
		(stroke
			(width 0)
			(type default)
		)
	)
	(wire
		(pts
			(xy 115.57 208.28) (xy 123.19 208.28)
		)
		(stroke
			(width 0)
			(type default)
		)
	)
	(wire
		(pts
			(xy 182.88 31.75) (xy 184.15 31.75)
		)
		(stroke
			(width 0)
			(type default)
		)
	)
	(wire
		(pts
			(xy 382.27 149.86) (xy 383.54 149.86)
		)
		(stroke
			(width 0)
			(type default)
		)
	)
	(wire
		(pts
			(xy 36.83 245.11) (xy 36.83 243.84)
		)
		(stroke
			(width 0)
			(type default)
		)
	)
	(wire
		(pts
			(xy 223.52 213.36) (xy 223.52 219.71)
		)
		(stroke
			(width 0)
			(type default)
		)
	)
	(wire
		(pts
			(xy 151.13 80.01) (xy 184.15 80.01)
		)
		(stroke
			(width 0)
			(type default)
		)
	)
	(wire
		(pts
			(xy 383.54 24.13) (xy 386.08 24.13)
		)
		(stroke
			(width 0)
			(type default)
		)
	)
	(wire
		(pts
			(xy 82.55 172.72) (xy 86.36 172.72)
		)
		(stroke
			(width 0)
			(type default)
		)
	)
	(wire
		(pts
			(xy 382.27 55.88) (xy 383.54 55.88)
		)
		(stroke
			(width 0)
			(type default)
		)
	)
	(wire
		(pts
			(xy 186.69 181.61) (xy 187.96 181.61)
		)
		(stroke
			(width 0)
			(type default)
		)
	)
	(wire
		(pts
			(xy 46.99 198.12) (xy 95.25 198.12)
		)
		(stroke
			(width 0)
			(type default)
		)
	)
	(wire
		(pts
			(xy 382.27 154.94) (xy 383.54 154.94)
		)
		(stroke
			(width 0)
			(type default)
		)
	)
	(wire
		(pts
			(xy 186.69 173.99) (xy 187.96 173.99)
		)
		(stroke
			(width 0)
			(type default)
		)
	)
	(wire
		(pts
			(xy 306.07 38.1) (xy 309.88 38.1)
		)
		(stroke
			(width 0)
			(type default)
		)
	)
	(wire
		(pts
			(xy 237.49 58.42) (xy 243.84 58.42)
		)
		(stroke
			(width 0)
			(type default)
		)
	)
	(wire
		(pts
			(xy 138.43 25.4) (xy 130.81 25.4)
		)
		(stroke
			(width 0)
			(type default)
		)
	)
	(wire
		(pts
			(xy 382.27 48.26) (xy 387.35 48.26)
		)
		(stroke
			(width 0)
			(type default)
		)
	)
	(wire
		(pts
			(xy 341.63 38.1) (xy 349.25 38.1)
		)
		(stroke
			(width 0)
			(type default)
		)
	)
	(wire
		(pts
			(xy 147.32 39.37) (xy 147.32 40.64)
		)
		(stroke
			(width 0)
			(type default)
		)
	)
	(wire
		(pts
			(xy 161.29 95.25) (xy 168.91 95.25)
		)
		(stroke
			(width 0)
			(type default)
		)
	)
	(wire
		(pts
			(xy 168.91 207.01) (xy 177.8 207.01)
		)
		(stroke
			(width 0)
			(type default)
		)
	)
	(wire
		(pts
			(xy 110.49 229.87) (xy 106.68 229.87)
		)
		(stroke
			(width 0)
			(type default)
		)
	)
	(wire
		(pts
			(xy 184.15 44.45) (xy 182.88 44.45)
		)
		(stroke
			(width 0)
			(type default)
		)
	)
	(wire
		(pts
			(xy 175.26 95.25) (xy 184.15 95.25)
		)
		(stroke
			(width 0)
			(type default)
		)
	)
	(wire
		(pts
			(xy 382.27 68.58) (xy 383.54 68.58)
		)
		(stroke
			(width 0)
			(type default)
		)
	)
	(wire
		(pts
			(xy 116.84 182.88) (xy 115.57 182.88)
		)
		(stroke
			(width 0)
			(type default)
		)
	)
	(wire
		(pts
			(xy 173.99 95.25) (xy 175.26 95.25)
		)
		(stroke
			(width 0)
			(type default)
		)
	)
	(wire
		(pts
			(xy 66.04 231.14) (xy 66.04 229.87)
		)
		(stroke
			(width 0)
			(type default)
		)
	)
	(wire
		(pts
			(xy 49.53 200.66) (xy 95.25 200.66)
		)
		(stroke
			(width 0)
			(type default)
		)
	)
	(wire
		(pts
			(xy 35.56 229.87) (xy 43.18 229.87)
		)
		(stroke
			(width 0)
			(type default)
		)
	)
	(wire
		(pts
			(xy 53.34 203.2) (xy 31.75 203.2)
		)
		(stroke
			(width 0)
			(type default)
		)
	)
	(wire
		(pts
			(xy 382.27 86.36) (xy 383.54 86.36)
		)
		(stroke
			(width 0)
			(type default)
		)
	)
	(wire
		(pts
			(xy 358.14 137.16) (xy 356.87 137.16)
		)
		(stroke
			(width 0)
			(type default)
		)
	)
	(wire
		(pts
			(xy 400.05 24.13) (xy 400.05 25.4)
		)
		(stroke
			(width 0)
			(type default)
		)
	)
	(wire
		(pts
			(xy 261.62 64.77) (xy 261.62 67.31)
		)
		(stroke
			(width 0)
			(type default)
		)
	)
	(wire
		(pts
			(xy 74.93 252.73) (xy 74.93 255.27)
		)
		(stroke
			(width 0)
			(type default)
		)
	)
	(wire
		(pts
			(xy 137.16 242.57) (xy 137.16 275.59)
		)
		(stroke
			(width 0)
			(type default)
		)
	)
	(wire
		(pts
			(xy 133.35 95.25) (xy 134.62 95.25)
		)
		(stroke
			(width 0)
			(type default)
		)
	)
	(wire
		(pts
			(xy 49.53 200.66) (xy 49.53 182.88)
		)
		(stroke
			(width 0)
			(type default)
		)
	)
	(wire
		(pts
			(xy 33.02 55.88) (xy 39.37 55.88)
		)
		(stroke
			(width 0)
			(type default)
		)
	)
	(wire
		(pts
			(xy 53.34 177.8) (xy 53.34 172.72)
		)
		(stroke
			(width 0)
			(type default)
		)
	)
	(wire
		(pts
			(xy 187.96 217.17) (xy 184.15 217.17)
		)
		(stroke
			(width 0)
			(type default)
		)
	)
	(wire
		(pts
			(xy 115.57 195.58) (xy 123.19 195.58)
		)
		(stroke
			(width 0)
			(type default)
		)
	)
	(wire
		(pts
			(xy 153.67 82.55) (xy 153.67 88.9)
		)
		(stroke
			(width 0)
			(type default)
		)
	)
	(wire
		(pts
			(xy 393.7 38.1) (xy 393.7 39.37)
		)
		(stroke
			(width 0)
			(type default)
		)
	)
	(wire
		(pts
			(xy 193.04 270.51) (xy 194.31 270.51)
		)
		(stroke
			(width 0)
			(type default)
		)
	)
	(wire
		(pts
			(xy 41.91 36.83) (xy 52.07 36.83)
		)
		(stroke
			(width 0)
			(type default)
		)
	)
	(wire
		(pts
			(xy 160.02 123.19) (xy 160.02 125.73)
		)
		(stroke
			(width 0)
			(type default)
		)
	)
	(wire
		(pts
			(xy 382.27 160.02) (xy 383.54 160.02)
		)
		(stroke
			(width 0)
			(type default)
		)
	)
	(wire
		(pts
			(xy 104.14 252.73) (xy 147.32 252.73)
		)
		(stroke
			(width 0)
			(type default)
		)
	)
	(wire
		(pts
			(xy 148.59 87.63) (xy 148.59 88.9)
		)
		(stroke
			(width 0)
			(type default)
		)
	)
	(wire
		(pts
			(xy 226.06 58.42) (xy 226.06 60.96)
		)
		(stroke
			(width 0)
			(type default)
		)
	)
	(wire
		(pts
			(xy 400.05 116.84) (xy 400.05 118.11)
		)
		(stroke
			(width 0)
			(type default)
		)
	)
	(wire
		(pts
			(xy 347.98 86.36) (xy 345.44 86.36)
		)
		(stroke
			(width 0)
			(type default)
		)
	)
	(wire
		(pts
			(xy 175.26 39.37) (xy 175.26 40.64)
		)
		(stroke
			(width 0)
			(type default)
		)
	)
	(wire
		(pts
			(xy 208.28 179.07) (xy 207.01 179.07)
		)
		(stroke
			(width 0)
			(type default)
		)
	)
	(wire
		(pts
			(xy 74.93 229.87) (xy 74.93 243.84)
		)
		(stroke
			(width 0)
			(type default)
		)
	)
	(wire
		(pts
			(xy 322.58 179.07) (xy 323.85 179.07)
		)
		(stroke
			(width 0)
			(type default)
		)
	)
	(wire
		(pts
			(xy 345.44 177.8) (xy 345.44 181.61)
		)
		(stroke
			(width 0)
			(type default)
		)
	)
	(wire
		(pts
			(xy 40.64 177.8) (xy 40.64 172.72)
		)
		(stroke
			(width 0)
			(type default)
		)
	)
	(wire
		(pts
			(xy 134.62 92.71) (xy 134.62 95.25)
		)
		(stroke
			(width 0)
			(type default)
		)
	)
	(wire
		(pts
			(xy 393.7 116.84) (xy 393.7 118.11)
		)
		(stroke
			(width 0)
			(type default)
		)
	)
	(wire
		(pts
			(xy 382.27 144.78) (xy 383.54 144.78)
		)
		(stroke
			(width 0)
			(type default)
		)
	)
	(wire
		(pts
			(xy 97.79 267.97) (xy 125.73 267.97)
		)
		(stroke
			(width 0)
			(type default)
		)
	)
	(wire
		(pts
			(xy 400.05 116.84) (xy 393.7 116.84)
		)
		(stroke
			(width 0)
			(type default)
		)
	)
	(wire
		(pts
			(xy 133.35 273.05) (xy 147.32 273.05)
		)
		(stroke
			(width 0)
			(type default)
		)
	)
	(wire
		(pts
			(xy 59.69 172.72) (xy 55.88 172.72)
		)
		(stroke
			(width 0)
			(type default)
		)
	)
	(wire
		(pts
			(xy 264.16 36.83) (xy 275.59 36.83)
		)
		(stroke
			(width 0)
			(type default)
		)
	)
	(wire
		(pts
			(xy 64.77 96.52) (xy 54.61 96.52)
		)
		(stroke
			(width 0)
			(type default)
		)
	)
	(wire
		(pts
			(xy 182.88 54.61) (xy 184.15 54.61)
		)
		(stroke
			(width 0)
			(type default)
		)
	)
	(wire
		(pts
			(xy 161.29 25.4) (xy 161.29 34.29)
		)
		(stroke
			(width 0)
			(type default)
		)
	)
	(wire
		(pts
			(xy 226.06 60.96) (xy 226.06 63.5)
		)
		(stroke
			(width 0)
			(type default)
		)
	)
	(wire
		(pts
			(xy 130.81 21.59) (xy 138.43 21.59)
		)
		(stroke
			(width 0)
			(type default)
		)
	)
	(wire
		(pts
			(xy 356.87 180.34) (xy 358.14 180.34)
		)
		(stroke
			(width 0)
			(type default)
		)
	)
	(wire
		(pts
			(xy 342.9 144.78) (xy 358.14 144.78)
		)
		(stroke
			(width 0)
			(type default)
		)
	)
	(wire
		(pts
			(xy 46.99 172.72) (xy 49.53 172.72)
		)
		(stroke
			(width 0)
			(type default)
		)
	)
	(wire
		(pts
			(xy 323.85 176.53) (xy 322.58 176.53)
		)
		(stroke
			(width 0)
			(type default)
		)
	)
	(wire
		(pts
			(xy 97.79 278.13) (xy 140.97 278.13)
		)
		(stroke
			(width 0)
			(type default)
		)
	)
	(wire
		(pts
			(xy 382.27 58.42) (xy 383.54 58.42)
		)
		(stroke
			(width 0)
			(type default)
		)
	)
	(wire
		(pts
			(xy 167.64 21.59) (xy 167.64 22.86)
		)
		(stroke
			(width 0)
			(type default)
		)
	)
	(wire
		(pts
			(xy 353.06 177.8) (xy 358.14 177.8)
		)
		(stroke
			(width 0)
			(type default)
		)
	)
	(wire
		(pts
			(xy 121.92 229.87) (xy 118.11 229.87)
		)
		(stroke
			(width 0)
			(type default)
		)
	)
	(wire
		(pts
			(xy 146.05 118.11) (xy 146.05 125.73)
		)
		(stroke
			(width 0)
			(type default)
		)
	)
	(wire
		(pts
			(xy 123.19 21.59) (xy 125.73 21.59)
		)
		(stroke
			(width 0)
			(type default)
		)
	)
	(wire
		(pts
			(xy 349.25 38.1) (xy 356.87 38.1)
		)
		(stroke
			(width 0)
			(type default)
		)
	)
	(wire
		(pts
			(xy 186.69 189.23) (xy 187.96 189.23)
		)
		(stroke
			(width 0)
			(type default)
		)
	)
	(wire
		(pts
			(xy 382.27 139.7) (xy 387.35 139.7)
		)
		(stroke
			(width 0)
			(type default)
		)
	)
	(wire
		(pts
			(xy 118.11 242.57) (xy 118.11 262.89)
		)
		(stroke
			(width 0)
			(type default)
		)
	)
	(wire
		(pts
			(xy 146.05 118.11) (xy 184.15 118.11)
		)
		(stroke
			(width 0)
			(type default)
		)
	)
	(wire
		(pts
			(xy 43.18 229.87) (xy 43.18 231.14)
		)
		(stroke
			(width 0)
			(type default)
		)
	)
	(wire
		(pts
			(xy 148.59 87.63) (xy 143.51 87.63)
		)
		(stroke
			(width 0)
			(type default)
		)
	)
	(wire
		(pts
			(xy 234.95 34.29) (xy 266.7 34.29)
		)
		(stroke
			(width 0)
			(type default)
		)
	)
	(wire
		(pts
			(xy 36.83 53.34) (xy 33.02 53.34)
		)
		(stroke
			(width 0)
			(type default)
		)
	)
	(wire
		(pts
			(xy 208.28 198.12) (xy 207.01 198.12)
		)
		(stroke
			(width 0)
			(type default)
		)
	)
	(wire
		(pts
			(xy 35.56 229.87) (xy 35.56 231.14)
		)
		(stroke
			(width 0)
			(type default)
		)
	)
	(wire
		(pts
			(xy 40.64 193.04) (xy 31.75 193.04)
		)
		(stroke
			(width 0)
			(type default)
		)
	)
	(wire
		(pts
			(xy 212.09 128.27) (xy 213.36 128.27)
		)
		(stroke
			(width 0)
			(type default)
		)
	)
	(wire
		(pts
			(xy 46.99 245.11) (xy 46.99 243.84)
		)
		(stroke
			(width 0)
			(type default)
		)
	)
	(wire
		(pts
			(xy 227.33 53.34) (xy 226.06 53.34)
		)
		(stroke
			(width 0)
			(type default)
		)
	)
	(wire
		(pts
			(xy 97.79 255.27) (xy 106.68 255.27)
		)
		(stroke
			(width 0)
			(type default)
		)
	)
	(wire
		(pts
			(xy 349.25 129.54) (xy 349.25 132.08)
		)
		(stroke
			(width 0)
			(type default)
		)
	)
	(wire
		(pts
			(xy 63.5 21.59) (xy 63.5 36.83)
		)
		(stroke
			(width 0)
			(type default)
		)
	)
	(wire
		(pts
			(xy 153.67 39.37) (xy 161.29 39.37)
		)
		(stroke
			(width 0)
			(type default)
		)
	)
	(wire
		(pts
			(xy 227.33 55.88) (xy 226.06 55.88)
		)
		(stroke
			(width 0)
			(type default)
		)
	)
	(wire
		(pts
			(xy 214.63 207.01) (xy 214.63 208.28)
		)
		(stroke
			(width 0)
			(type default)
		)
	)
	(wire
		(pts
			(xy 349.25 38.1) (xy 349.25 39.37)
		)
		(stroke
			(width 0)
			(type default)
		)
	)
	(wire
		(pts
			(xy 210.82 217.17) (xy 210.82 207.01)
		)
		(stroke
			(width 0)
			(type default)
		)
	)
	(wire
		(pts
			(xy 260.35 39.37) (xy 275.59 39.37)
		)
		(stroke
			(width 0)
			(type default)
		)
	)
	(wire
		(pts
			(xy 27.94 245.11) (xy 27.94 243.84)
		)
		(stroke
			(width 0)
			(type default)
		)
	)
	(wire
		(pts
			(xy 31.75 190.5) (xy 36.83 190.5)
		)
		(stroke
			(width 0)
			(type default)
		)
	)
	(wire
		(pts
			(xy 388.62 116.84) (xy 393.7 116.84)
		)
		(stroke
			(width 0)
			(type default)
		)
	)
	(wire
		(pts
			(xy 342.9 154.94) (xy 347.98 154.94)
		)
		(stroke
			(width 0)
			(type default)
		)
	)
	(wire
		(pts
			(xy 57.15 243.84) (xy 66.04 243.84)
		)
		(stroke
			(width 0)
			(type default)
		)
	)
	(wire
		(pts
			(xy 153.67 54.61) (xy 161.29 54.61)
		)
		(stroke
			(width 0)
			(type default)
		)
	)
	(wire
		(pts
			(xy 254 53.34) (xy 260.35 53.34)
		)
		(stroke
			(width 0)
			(type default)
		)
	)
	(wire
		(pts
			(xy 345.44 86.36) (xy 345.44 90.17)
		)
		(stroke
			(width 0)
			(type default)
		)
	)
	(wire
		(pts
			(xy 143.51 25.4) (xy 147.32 25.4)
		)
		(stroke
			(width 0)
			(type default)
		)
	)
	(wire
		(pts
			(xy 193.04 260.35) (xy 194.31 260.35)
		)
		(stroke
			(width 0)
			(type default)
		)
	)
	(wire
		(pts
			(xy 237.49 53.34) (xy 254 53.34)
		)
		(stroke
			(width 0)
			(type default)
		)
	)
	(wire
		(pts
			(xy 243.84 58.42) (xy 243.84 66.04)
		)
		(stroke
			(width 0)
			(type default)
		)
	)
	(wire
		(pts
			(xy 143.51 87.63) (xy 143.51 93.98)
		)
		(stroke
			(width 0)
			(type default)
		)
	)
	(wire
		(pts
			(xy 215.9 77.47) (xy 215.9 88.9)
		)
		(stroke
			(width 0)
			(type default)
		)
	)
	(wire
		(pts
			(xy 317.5 38.1) (xy 317.5 39.37)
		)
		(stroke
			(width 0)
			(type default)
		)
	)
	(wire
		(pts
			(xy 66.04 257.81) (xy 58.42 257.81)
		)
		(stroke
			(width 0)
			(type default)
		)
	)
	(wire
		(pts
			(xy 349.25 44.45) (xy 349.25 48.26)
		)
		(stroke
			(width 0)
			(type default)
		)
	)
	(wire
		(pts
			(xy 212.09 74.93) (xy 217.17 74.93)
		)
		(stroke
			(width 0)
			(type default)
		)
	)
	(wire
		(pts
			(xy 77.47 252.73) (xy 74.93 252.73)
		)
		(stroke
			(width 0)
			(type default)
		)
	)
	(wire
		(pts
			(xy 161.29 39.37) (xy 167.64 39.37)
		)
		(stroke
			(width 0)
			(type default)
		)
	)
	(wire
		(pts
			(xy 184.15 167.64) (xy 184.15 158.75)
		)
		(stroke
			(width 0)
			(type default)
		)
	)
	(wire
		(pts
			(xy 115.57 203.2) (xy 123.19 203.2)
		)
		(stroke
			(width 0)
			(type default)
		)
	)
	(wire
		(pts
			(xy 48.26 21.59) (xy 48.26 22.86)
		)
		(stroke
			(width 0)
			(type default)
		)
	)
	(wire
		(pts
			(xy 358.14 45.72) (xy 356.87 45.72)
		)
		(stroke
			(width 0)
			(type default)
		)
	)
	(wire
		(pts
			(xy 63.5 36.83) (xy 60.96 36.83)
		)
		(stroke
			(width 0)
			(type default)
		)
	)
	(wire
		(pts
			(xy 208.28 189.23) (xy 207.01 189.23)
		)
		(stroke
			(width 0)
			(type default)
		)
	)
	(wire
		(pts
			(xy 342.9 147.32) (xy 358.14 147.32)
		)
		(stroke
			(width 0)
			(type default)
		)
	)
	(wire
		(pts
			(xy 74.93 255.27) (xy 77.47 255.27)
		)
		(stroke
			(width 0)
			(type default)
		)
	)
	(wire
		(pts
			(xy 40.64 193.04) (xy 95.25 193.04)
		)
		(stroke
			(width 0)
			(type default)
		)
	)
	(wire
		(pts
			(xy 140.97 229.87) (xy 140.97 237.49)
		)
		(stroke
			(width 0)
			(type default)
		)
	)
	(wire
		(pts
			(xy 55.88 205.74) (xy 55.88 182.88)
		)
		(stroke
			(width 0)
			(type default)
		)
	)
	(wire
		(pts
			(xy 386.08 24.13) (xy 386.08 25.4)
		)
		(stroke
			(width 0)
			(type default)
		)
	)
	(wire
		(pts
			(xy 353.06 63.5) (xy 358.14 63.5)
		)
		(stroke
			(width 0)
			(type default)
		)
	)
	(wire
		(pts
			(xy 207.01 170.18) (xy 223.52 170.18)
		)
		(stroke
			(width 0)
			(type default)
		)
	)
	(wire
		(pts
			(xy 193.04 267.97) (xy 194.31 267.97)
		)
		(stroke
			(width 0)
			(type default)
		)
	)
	(wire
		(pts
			(xy 66.04 245.11) (xy 66.04 243.84)
		)
		(stroke
			(width 0)
			(type default)
		)
	)
	(wire
		(pts
			(xy 36.83 190.5) (xy 95.25 190.5)
		)
		(stroke
			(width 0)
			(type default)
		)
	)
	(wire
		(pts
			(xy 223.52 158.75) (xy 223.52 160.02)
		)
		(stroke
			(width 0)
			(type default)
		)
	)
	(wire
		(pts
			(xy 27.94 36.83) (xy 34.29 36.83)
		)
		(stroke
			(width 0)
			(type default)
		)
	)
	(wire
		(pts
			(xy 121.92 265.43) (xy 147.32 265.43)
		)
		(stroke
			(width 0)
			(type default)
		)
	)
	(wire
		(pts
			(xy 167.64 54.61) (xy 182.88 54.61)
		)
		(stroke
			(width 0)
			(type default)
		)
	)
	(wire
		(pts
			(xy 160.02 127) (xy 160.02 125.73)
		)
		(stroke
			(width 0)
			(type default)
		)
	)
	(wire
		(pts
			(xy 208.28 195.58) (xy 208.28 198.12)
		)
		(stroke
			(width 0)
			(type default)
		)
	)
	(wire
		(pts
			(xy 175.26 125.73) (xy 175.26 127)
		)
		(stroke
			(width 0)
			(type default)
		)
	)
	(wire
		(pts
			(xy 40.64 172.72) (xy 43.18 172.72)
		)
		(stroke
			(width 0)
			(type default)
		)
	)
	(wire
		(pts
			(xy 41.91 53.34) (xy 64.77 53.34)
		)
		(stroke
			(width 0)
			(type default)
		)
	)
	(wire
		(pts
			(xy 118.11 262.89) (xy 147.32 262.89)
		)
		(stroke
			(width 0)
			(type default)
		)
	)
	(wire
		(pts
			(xy 25.4 21.59) (xy 27.94 21.59)
		)
		(stroke
			(width 0)
			(type default)
		)
	)
	(wire
		(pts
			(xy 213.36 128.27) (xy 213.36 132.08)
		)
		(stroke
			(width 0)
			(type default)
		)
	)
	(wire
		(pts
			(xy 382.27 175.26) (xy 383.54 175.26)
		)
		(stroke
			(width 0)
			(type default)
		)
	)
	(wire
		(pts
			(xy 382.27 78.74) (xy 383.54 78.74)
		)
		(stroke
			(width 0)
			(type default)
		)
	)
	(wire
		(pts
			(xy 383.54 116.84) (xy 383.54 137.16)
		)
		(stroke
			(width 0)
			(type default)
		)
	)
	(wire
		(pts
			(xy 59.69 208.28) (xy 95.25 208.28)
		)
		(stroke
			(width 0)
			(type default)
		)
	)
	(wire
		(pts
			(xy 358.14 55.88) (xy 342.9 55.88)
		)
		(stroke
			(width 0)
			(type default)
		)
	)
	(wire
		(pts
			(xy 60.96 36.83) (xy 60.96 38.1)
		)
		(stroke
			(width 0)
			(type default)
		)
	)
	(wire
		(pts
			(xy 212.09 36.83) (xy 229.87 36.83)
		)
		(stroke
			(width 0)
			(type default)
		)
	)
	(wire
		(pts
			(xy 341.63 129.54) (xy 349.25 129.54)
		)
		(stroke
			(width 0)
			(type default)
		)
	)
	(wire
		(pts
			(xy 207.01 167.64) (xy 210.82 167.64)
		)
		(stroke
			(width 0)
			(type default)
		)
	)
	(wire
		(pts
			(xy 147.32 54.61) (xy 153.67 54.61)
		)
		(stroke
			(width 0)
			(type default)
		)
	)
	(wire
		(pts
			(xy 167.64 21.59) (xy 175.26 21.59)
		)
		(stroke
			(width 0)
			(type default)
		)
	)
	(wire
		(pts
			(xy 175.26 39.37) (xy 182.88 39.37)
		)
		(stroke
			(width 0)
			(type default)
		)
	)
	(wire
		(pts
			(xy 208.28 176.53) (xy 207.01 176.53)
		)
		(stroke
			(width 0)
			(type default)
		)
	)
	(wire
		(pts
			(xy 212.09 125.73) (xy 213.36 125.73)
		)
		(stroke
			(width 0)
			(type default)
		)
	)
	(wire
		(pts
			(xy 226.06 66.04) (xy 226.06 67.31)
		)
		(stroke
			(width 0)
			(type default)
		)
	)
	(wire
		(pts
			(xy 74.93 278.13) (xy 74.93 279.4)
		)
		(stroke
			(width 0)
			(type default)
		)
	)
	(wire
		(pts
			(xy 41.91 36.83) (xy 41.91 38.1)
		)
		(stroke
			(width 0)
			(type default)
		)
	)
	(wire
		(pts
			(xy 175.26 21.59) (xy 181.61 21.59)
		)
		(stroke
			(width 0)
			(type default)
		)
	)
	(wire
		(pts
			(xy 160.02 123.19) (xy 184.15 123.19)
		)
		(stroke
			(width 0)
			(type default)
		)
	)
	(wire
		(pts
			(xy 147.32 25.4) (xy 154.94 25.4)
		)
		(stroke
			(width 0)
			(type default)
		)
	)
	(wire
		(pts
			(xy 154.94 25.4) (xy 156.21 25.4)
		)
		(stroke
			(width 0)
			(type default)
		)
	)
	(wire
		(pts
			(xy 387.35 48.26) (xy 388.62 48.26)
		)
		(stroke
			(width 0)
			(type default)
		)
	)
	(wire
		(pts
			(xy 49.53 200.66) (xy 31.75 200.66)
		)
		(stroke
			(width 0)
			(type default)
		)
	)
	(wire
		(pts
			(xy 342.9 173.99) (xy 358.14 173.99)
		)
		(stroke
			(width 0)
			(type default)
		)
	)
	(wire
		(pts
			(xy 382.27 53.34) (xy 383.54 53.34)
		)
		(stroke
			(width 0)
			(type default)
		)
	)
	(wire
		(pts
			(xy 317.5 129.54) (xy 317.5 130.81)
		)
		(stroke
			(width 0)
			(type default)
		)
	)
	(wire
		(pts
			(xy 353.06 154.94) (xy 358.14 154.94)
		)
		(stroke
			(width 0)
			(type default)
		)
	)
	(wire
		(pts
			(xy 326.39 129.54) (xy 326.39 130.81)
		)
		(stroke
			(width 0)
			(type default)
		)
	)
	(wire
		(pts
			(xy 323.85 85.09) (xy 322.58 85.09)
		)
		(stroke
			(width 0)
			(type default)
		)
	)
	(wire
		(pts
			(xy 133.35 229.87) (xy 133.35 237.49)
		)
		(stroke
			(width 0)
			(type default)
		)
	)
	(wire
		(pts
			(xy 161.29 54.61) (xy 167.64 54.61)
		)
		(stroke
			(width 0)
			(type default)
		)
	)
	(wire
		(pts
			(xy 208.28 223.52) (xy 207.01 223.52)
		)
		(stroke
			(width 0)
			(type default)
		)
	)
	(wire
		(pts
			(xy 208.28 181.61) (xy 207.01 181.61)
		)
		(stroke
			(width 0)
			(type default)
		)
	)
	(wire
		(pts
			(xy 241.3 60.96) (xy 266.7 60.96)
		)
		(stroke
			(width 0)
			(type default)
		)
	)
	(wire
		(pts
			(xy 66.04 257.81) (xy 77.47 257.81)
		)
		(stroke
			(width 0)
			(type default)
		)
	)
	(wire
		(pts
			(xy 129.54 270.51) (xy 147.32 270.51)
		)
		(stroke
			(width 0)
			(type default)
		)
	)
	(wire
		(pts
			(xy 44.45 55.88) (xy 64.77 55.88)
		)
		(stroke
			(width 0)
			(type default)
		)
	)
	(wire
		(pts
			(xy 125.73 21.59) (xy 130.81 21.59)
		)
		(stroke
			(width 0)
			(type default)
		)
	)
	(label "FT_VPHY"
		(at 147.32 21.59 0)
		(effects
			(font
				(size 1.27 1.27)
			)
			(justify left bottom)
		)
	)
	(label "VBUS"
		(at 161.29 95.25 0)
		(effects
			(font
				(size 1.27 1.27)
			)
			(justify left bottom)
		)
	)
	(label "PCIE_BMC_TX_C_P"
		(at 48.26 53.34 0)
		(effects
			(font
				(size 1.27 1.27)
			)
			(justify left bottom)
		)
	)
	(label "PCIE_BMC_TX_C_N"
		(at 48.26 55.88 0)
		(effects
			(font
				(size 1.27 1.27)
			)
			(justify left bottom)
		)
	)
	(label "FT_VPLL"
		(at 147.32 25.4 0)
		(effects
			(font
				(size 1.27 1.27)
			)
			(justify left bottom)
		)
	)
	(label "DBG_USB_D_P"
		(at 179.07 80.01 180)
		(effects
			(font
				(size 1.27 1.27)
			)
			(justify right bottom)
		)
	)
	(label "VBUS"
		(at 142.24 74.93 180)
		(effects
			(font
				(size 1.27 1.27)
			)
			(justify right bottom)
		)
	)
	(label "DBG_USB_D_N"
		(at 179.07 82.55 180)
		(effects
			(font
				(size 1.27 1.27)
			)
			(justify right bottom)
		)
	)
	(label "1V0_EN"
		(at 93.98 172.72 180)
		(effects
			(font
				(size 1.27 1.27)
			)
			(justify right bottom)
		)
	)
	(global_label "MMC_CMD"
		(shape input)
		(at 147.32 257.81 0)
		(fields_autoplaced yes)
		(effects
			(font
				(size 1.27 1.27)
			)
			(justify left)
		)
		(property "Intersheetrefs" "${INTERSHEET_REFS}"
			(at -22.225 3.81 0)
			(effects
				(font
					(size 1.27 1.27)
				)
				(hide yes)
			)
		)
	)
	(global_label "ULPI2_DIR"
		(shape output)
		(at 383.54 170.18 0)
		(fields_autoplaced yes)
		(effects
			(font
				(size 1.27 1.27)
			)
			(justify left)
		)
		(property "Intersheetrefs" "${INTERSHEET_REFS}"
			(at 395.4194 170.1006 0)
			(effects
				(font
					(size 1.27 1.27)
				)
				(justify left)
				(hide yes)
			)
		)
	)
	(global_label "MMC_DAT6"
		(shape input)
		(at 147.32 275.59 0)
		(fields_autoplaced yes)
		(effects
			(font
				(size 1.27 1.27)
			)
			(justify left)
		)
		(property "Intersheetrefs" "${INTERSHEET_REFS}"
			(at -22.225 3.81 0)
			(effects
				(font
					(size 1.27 1.27)
				)
				(hide yes)
			)
		)
	)
	(global_label "I3C[1]_SDA"
		(shape input)
		(at 123.19 198.12 0)
		(fields_autoplaced yes)
		(effects
			(font
				(size 1.27 1.27)
			)
			(justify left)
		)
		(property "Intersheetrefs" "${INTERSHEET_REFS}"
			(at -6.35 13.97 0)
			(effects
				(font
					(size 1.27 1.27)
				)
				(hide yes)
			)
		)
	)
	(global_label "ESPI_IO3_1V8"
		(shape input)
		(at 186.69 191.77 180)
		(fields_autoplaced yes)
		(effects
			(font
				(size 1.27 1.27)
			)
			(justify right)
		)
		(property "Intersheetrefs" "${INTERSHEET_REFS}"
			(at -4.445 0 0)
			(effects
				(font
					(size 1.27 1.27)
				)
				(hide yes)
			)
		)
	)
	(global_label "USB1_D_N"
		(shape input)
		(at 342.9 53.34 180)
		(fields_autoplaced yes)
		(effects
			(font
				(size 1.27 1.27)
			)
			(justify right)
		)
		(property "Intersheetrefs" "${INTERSHEET_REFS}"
			(at 39.37 -31.75 0)
			(effects
				(font
					(size 1.27 1.27)
				)
				(hide yes)
			)
		)
	)
	(global_label "I3C[0]_SDA_3V3"
		(shape input)
		(at 31.75 193.04 180)
		(fields_autoplaced yes)
		(effects
			(font
				(size 1.27 1.27)
			)
			(justify right)
		)
		(property "Intersheetrefs" "${INTERSHEET_REFS}"
			(at -8.89 -2.54 0)
			(effects
				(font
					(size 1.27 1.27)
				)
				(justify right)
				(hide yes)
			)
		)
	)
	(global_label "ULPI1_DATA3"
		(shape input)
		(at 383.54 60.96 0)
		(fields_autoplaced yes)
		(effects
			(font
				(size 1.27 1.27)
			)
			(justify left)
		)
		(property "Intersheetrefs" "${INTERSHEET_REFS}"
			(at 15.24 160.02 0)
			(effects
				(font
					(size 1.27 1.27)
				)
				(hide yes)
			)
		)
	)
	(global_label "ULPI1_CLKOUT"
		(shape output)
		(at 383.54 83.82 0)
		(fields_autoplaced yes)
		(effects
			(font
				(size 1.27 1.27)
			)
			(justify left)
		)
		(property "Intersheetrefs" "${INTERSHEET_REFS}"
			(at 399.4713 83.7406 0)
			(effects
				(font
					(size 1.27 1.27)
				)
				(justify left)
				(hide yes)
			)
		)
	)
	(global_label "ULPI1_STP"
		(shape input)
		(at 383.54 81.28 0)
		(fields_autoplaced yes)
		(effects
			(font
				(size 1.27 1.27)
			)
			(justify left)
		)
		(property "Intersheetrefs" "${INTERSHEET_REFS}"
			(at 15.24 -33.02 0)
			(effects
				(font
					(size 1.27 1.27)
				)
				(hide yes)
			)
		)
	)
	(global_label "I3C[3]_SCL"
		(shape input)
		(at 123.19 205.74 0)
		(fields_autoplaced yes)
		(effects
			(font
				(size 1.27 1.27)
			)
			(justify left)
		)
		(property "Intersheetrefs" "${INTERSHEET_REFS}"
			(at -6.35 13.97 0)
			(effects
				(font
					(size 1.27 1.27)
				)
				(hide yes)
			)
		)
	)
	(global_label "ESPI_CLK"
		(shape input)
		(at 208.28 173.99 0)
		(fields_autoplaced yes)
		(effects
			(font
				(size 1.27 1.27)
			)
			(justify left)
		)
		(property "Intersheetrefs" "${INTERSHEET_REFS}"
			(at -6.985 0 0)
			(effects
				(font
					(size 1.27 1.27)
				)
				(hide yes)
			)
		)
	)
	(global_label "JTAG_TDI"
		(shape output)
		(at 275.59 34.29 0)
		(fields_autoplaced yes)
		(effects
			(font
				(size 1.27 1.27)
			)
			(justify left)
		)
		(property "Intersheetrefs" "${INTERSHEET_REFS}"
			(at 286.018 34.2106 0)
			(effects
				(font
					(size 1.27 1.27)
				)
				(justify left)
				(hide yes)
			)
		)
	)
	(global_label "USB2_D_N"
		(shape input)
		(at 342.9 144.78 180)
		(fields_autoplaced yes)
		(effects
			(font
				(size 1.27 1.27)
			)
			(justify right)
		)
		(property "Intersheetrefs" "${INTERSHEET_REFS}"
			(at 43.18 -51.435 0)
			(effects
				(font
					(size 1.27 1.27)
				)
				(hide yes)
			)
		)
	)
	(global_label "VCC3V3"
		(shape input)
		(at 123.19 21.59 180)
		(fields_autoplaced yes)
		(effects
			(font
				(size 1.27 1.27)
			)
			(justify right)
		)
		(property "Intersheetrefs" "${INTERSHEET_REFS}"
			(at 5.715 238.125 0)
			(effects
				(font
					(size 1.27 1.27)
				)
				(hide yes)
			)
		)
	)
	(global_label "ESPI_CS0_N"
		(shape input)
		(at 208.28 176.53 0)
		(fields_autoplaced yes)
		(effects
			(font
				(size 1.27 1.27)
			)
			(justify left)
		)
		(property "Intersheetrefs" "${INTERSHEET_REFS}"
			(at -6.985 0 0)
			(effects
				(font
					(size 1.27 1.27)
				)
				(hide yes)
			)
		)
	)
	(global_label "ULPI2_DATA2"
		(shape input)
		(at 383.54 149.86 0)
		(fields_autoplaced yes)
		(effects
			(font
				(size 1.27 1.27)
			)
			(justify left)
		)
		(property "Intersheetrefs" "${INTERSHEET_REFS}"
			(at 23.495 362.585 0)
			(effects
				(font
					(size 1.27 1.27)
				)
				(hide yes)
			)
		)
	)
	(global_label "ULPI1_DATA2"
		(shape input)
		(at 383.54 58.42 0)
		(fields_autoplaced yes)
		(effects
			(font
				(size 1.27 1.27)
			)
			(justify left)
		)
		(property "Intersheetrefs" "${INTERSHEET_REFS}"
			(at 15.24 160.02 0)
			(effects
				(font
					(size 1.27 1.27)
				)
				(hide yes)
			)
		)
	)
	(global_label "ULPI1_DATA4"
		(shape input)
		(at 383.54 63.5 0)
		(fields_autoplaced yes)
		(effects
			(font
				(size 1.27 1.27)
			)
			(justify left)
		)
		(property "Intersheetrefs" "${INTERSHEET_REFS}"
			(at 15.24 160.02 0)
			(effects
				(font
					(size 1.27 1.27)
				)
				(hide yes)
			)
		)
	)
	(global_label "USB1_D_P"
		(shape input)
		(at 342.9 55.88 180)
		(fields_autoplaced yes)
		(effects
			(font
				(size 1.27 1.27)
			)
			(justify right)
		)
		(property "Intersheetrefs" "${INTERSHEET_REFS}"
			(at 39.37 -31.75 0)
			(effects
				(font
					(size 1.27 1.27)
				)
				(hide yes)
			)
		)
	)
	(global_label "ULPI1_DATA7"
		(shape input)
		(at 383.54 71.12 0)
		(fields_autoplaced yes)
		(effects
			(font
				(size 1.27 1.27)
			)
			(justify left)
		)
		(property "Intersheetrefs" "${INTERSHEET_REFS}"
			(at 15.24 160.02 0)
			(effects
				(font
					(size 1.27 1.27)
				)
				(hide yes)
			)
		)
	)
	(global_label "ULPI2_RESET"
		(shape input)
		(at 383.54 177.8 0)
		(fields_autoplaced yes)
		(effects
			(font
				(size 1.27 1.27)
			)
			(justify left)
		)
		(property "Intersheetrefs" "${INTERSHEET_REFS}"
			(at 23.495 -52.705 0)
			(effects
				(font
					(size 1.27 1.27)
				)
				(hide yes)
			)
		)
	)
	(global_label "ULPI2_DATA3"
		(shape input)
		(at 383.54 152.4 0)
		(fields_autoplaced yes)
		(effects
			(font
				(size 1.27 1.27)
			)
			(justify left)
		)
		(property "Intersheetrefs" "${INTERSHEET_REFS}"
			(at 23.495 362.585 0)
			(effects
				(font
					(size 1.27 1.27)
				)
				(hide yes)
			)
		)
	)
	(global_label "I3C[2]_SCL"
		(shape input)
		(at 123.19 200.66 0)
		(fields_autoplaced yes)
		(effects
			(font
				(size 1.27 1.27)
			)
			(justify left)
		)
		(property "Intersheetrefs" "${INTERSHEET_REFS}"
			(at -6.35 13.97 0)
			(effects
				(font
					(size 1.27 1.27)
				)
				(hide yes)
			)
		)
	)
	(global_label "VCC3V3"
		(shape input)
		(at 306.07 129.54 180)
		(fields_autoplaced yes)
		(effects
			(font
				(size 1.27 1.27)
			)
			(justify right)
		)
		(property "Intersheetrefs" "${INTERSHEET_REFS}"
			(at 280.67 488.95 0)
			(effects
				(font
					(size 1.27 1.27)
				)
				(hide yes)
			)
		)
	)
	(global_label "JTAG_TDO"
		(shape output)
		(at 275.59 36.83 0)
		(fields_autoplaced yes)
		(effects
			(font
				(size 1.27 1.27)
			)
			(justify left)
		)
		(property "Intersheetrefs" "${INTERSHEET_REFS}"
			(at 286.7437 36.7506 0)
			(effects
				(font
					(size 1.27 1.27)
				)
				(justify left)
				(hide yes)
			)
		)
	)
	(global_label "ULPI2_DATA1"
		(shape input)
		(at 383.54 147.32 0)
		(fields_autoplaced yes)
		(effects
			(font
				(size 1.27 1.27)
			)
			(justify left)
		)
		(property "Intersheetrefs" "${INTERSHEET_REFS}"
			(at 23.495 362.585 0)
			(effects
				(font
					(size 1.27 1.27)
				)
				(hide yes)
			)
		)
	)
	(global_label "VCC1V8"
		(shape input)
		(at 168.91 207.01 180)
		(fields_autoplaced yes)
		(effects
			(font
				(size 1.27 1.27)
			)
			(justify right)
		)
		(property "Intersheetrefs" "${INTERSHEET_REFS}"
			(at -33.02 370.205 0)
			(effects
				(font
					(size 1.27 1.27)
				)
				(hide yes)
			)
		)
	)
	(global_label "ESPI_RESET_N"
		(shape input)
		(at 208.28 181.61 0)
		(fields_autoplaced yes)
		(effects
			(font
				(size 1.27 1.27)
			)
			(justify left)
		)
		(property "Intersheetrefs" "${INTERSHEET_REFS}"
			(at -6.985 0 0)
			(effects
				(font
					(size 1.27 1.27)
				)
				(hide yes)
			)
		)
	)
	(global_label "VCC5V0"
		(shape input)
		(at 342.9 63.5 180)
		(fields_autoplaced yes)
		(effects
			(font
				(size 1.27 1.27)
			)
			(justify right)
		)
		(property "Intersheetrefs" "${INTERSHEET_REFS}"
			(at 276.225 363.22 0)
			(effects
				(font
					(size 1.27 1.27)
				)
				(hide yes)
			)
		)
	)
	(global_label "PCIE_BMC_CLK_100_N"
		(shape input)
		(at 54.61 99.06 180)
		(fields_autoplaced yes)
		(effects
			(font
				(size 1.27 1.27)
			)
			(justify right)
		)
		(property "Intersheetrefs" "${INTERSHEET_REFS}"
			(at 3.81 15.875 0)
			(effects
				(font
					(size 1.27 1.27)
				)
				(hide yes)
			)
		)
	)
	(global_label "MMC_DAT5"
		(shape input)
		(at 147.32 273.05 0)
		(fields_autoplaced yes)
		(effects
			(font
				(size 1.27 1.27)
			)
			(justify left)
		)
		(property "Intersheetrefs" "${INTERSHEET_REFS}"
			(at -22.225 3.81 0)
			(effects
				(font
					(size 1.27 1.27)
				)
				(hide yes)
			)
		)
	)
	(global_label "JTAG_TMS"
		(shape output)
		(at 275.59 39.37 0)
		(fields_autoplaced yes)
		(effects
			(font
				(size 1.27 1.27)
			)
			(justify left)
		)
		(property "Intersheetrefs" "${INTERSHEET_REFS}"
			(at 286.8042 39.2906 0)
			(effects
				(font
					(size 1.27 1.27)
				)
				(justify left)
				(hide yes)
			)
		)
	)
	(global_label "ESPI_CS1_N"
		(shape input)
		(at 208.28 223.52 0)
		(fields_autoplaced yes)
		(effects
			(font
				(size 1.27 1.27)
			)
			(justify left)
		)
		(property "Intersheetrefs" "${INTERSHEET_REFS}"
			(at 401.32 445.135 0)
			(effects
				(font
					(size 1.27 1.27)
				)
				(hide yes)
			)
		)
	)
	(global_label "VCC3V3"
		(shape input)
		(at 311.15 82.55 180)
		(fields_autoplaced yes)
		(effects
			(font
				(size 1.27 1.27)
			)
			(justify right)
		)
		(property "Intersheetrefs" "${INTERSHEET_REFS}"
			(at 213.36 330.835 0)
			(effects
				(font
					(size 1.27 1.27)
				)
				(hide yes)
			)
		)
	)
	(global_label "ESPI_IO2_1V8"
		(shape input)
		(at 186.69 189.23 180)
		(fields_autoplaced yes)
		(effects
			(font
				(size 1.27 1.27)
			)
			(justify right)
		)
		(property "Intersheetrefs" "${INTERSHEET_REFS}"
			(at -4.445 0 0)
			(effects
				(font
					(size 1.27 1.27)
				)
				(hide yes)
			)
		)
	)
	(global_label "ULPI1_DATA6"
		(shape input)
		(at 383.54 68.58 0)
		(fields_autoplaced yes)
		(effects
			(font
				(size 1.27 1.27)
			)
			(justify left)
		)
		(property "Intersheetrefs" "${INTERSHEET_REFS}"
			(at 15.24 160.02 0)
			(effects
				(font
					(size 1.27 1.27)
				)
				(hide yes)
			)
		)
	)
	(global_label "PCIE_BMC_TX_N"
		(shape input)
		(at 33.02 55.88 180)
		(fields_autoplaced yes)
		(effects
			(font
				(size 1.27 1.27)
			)
			(justify right)
		)
		(property "Intersheetrefs" "${INTERSHEET_REFS}"
			(at 1.905 18.415 0)
			(effects
				(font
					(size 1.27 1.27)
				)
				(hide yes)
			)
		)
	)
	(global_label "I3C[0]_SCL_3V3"
		(shape input)
		(at 31.75 190.5 180)
		(fields_autoplaced yes)
		(effects
			(font
				(size 1.27 1.27)
			)
			(justify right)
		)
		(property "Intersheetrefs" "${INTERSHEET_REFS}"
			(at -8.89 -7.62 0)
			(effects
				(font
					(size 1.27 1.27)
				)
				(justify right)
				(hide yes)
			)
		)
	)
	(global_label "1V0_PG"
		(shape input)
		(at 73.66 172.72 180)
		(fields_autoplaced yes)
		(effects
			(font
				(size 1.27 1.27)
			)
			(justify right)
		)
		(property "Intersheetrefs" "${INTERSHEET_REFS}"
			(at -17.78 11.43 0)
			(effects
				(font
					(size 1.27 1.27)
				)
				(hide yes)
			)
		)
	)
	(global_label "ESPI_IO0_1V8"
		(shape input)
		(at 186.69 184.15 180)
		(fields_autoplaced yes)
		(effects
			(font
				(size 1.27 1.27)
			)
			(justify right)
		)
		(property "Intersheetrefs" "${INTERSHEET_REFS}"
			(at -4.445 0 0)
			(effects
				(font
					(size 1.27 1.27)
				)
				(hide yes)
			)
		)
	)
	(global_label "VCC3V3"
		(shape input)
		(at 22.86 229.87 180)
		(fields_autoplaced yes)
		(effects
			(font
				(size 1.27 1.27)
			)
			(justify right)
		)
		(property "Intersheetrefs" "${INTERSHEET_REFS}"
			(at -204.47 285.75 0)
			(effects
				(font
					(size 1.27 1.27)
				)
				(hide yes)
			)
		)
	)
	(global_label "PCIE_BMC_TX_P"
		(shape input)
		(at 33.02 53.34 180)
		(fields_autoplaced yes)
		(effects
			(font
				(size 1.27 1.27)
			)
			(justify right)
		)
		(property "Intersheetrefs" "${INTERSHEET_REFS}"
			(at 1.905 18.415 0)
			(effects
				(font
					(size 1.27 1.27)
				)
				(hide yes)
			)
		)
	)
	(global_label "I3C[0]_SDA"
		(shape input)
		(at 123.19 193.04 0)
		(fields_autoplaced yes)
		(effects
			(font
				(size 1.27 1.27)
			)
			(justify left)
		)
		(property "Intersheetrefs" "${INTERSHEET_REFS}"
			(at -6.35 13.97 0)
			(effects
				(font
					(size 1.27 1.27)
				)
				(hide yes)
			)
		)
	)
	(global_label "VCC3V3"
		(shape input)
		(at 193.04 260.35 180)
		(fields_autoplaced yes)
		(effects
			(font
				(size 1.27 1.27)
			)
			(justify right)
		)
		(property "Intersheetrefs" "${INTERSHEET_REFS}"
			(at -59.055 474.98 0)
			(effects
				(font
					(size 1.27 1.27)
				)
				(hide yes)
			)
		)
	)
	(global_label "I3C[2]_SDA_3V3"
		(shape input)
		(at 31.75 203.2 180)
		(fields_autoplaced yes)
		(effects
			(font
				(size 1.27 1.27)
			)
			(justify right)
		)
		(property "Intersheetrefs" "${INTERSHEET_REFS}"
			(at -8.89 -2.54 0)
			(effects
				(font
					(size 1.27 1.27)
				)
				(justify right)
				(hide yes)
			)
		)
	)
	(global_label "SPI0_CS_N"
		(shape input)
		(at 193.04 270.51 180)
		(fields_autoplaced yes)
		(effects
			(font
				(size 1.27 1.27)
			)
			(justify right)
		)
		(property "Intersheetrefs" "${INTERSHEET_REFS}"
			(at -24.765 3.175 0)
			(effects
				(font
					(size 1.27 1.27)
				)
				(hide yes)
			)
		)
	)
	(global_label "VCC1V8"
		(shape input)
		(at 168.91 158.75 180)
		(fields_autoplaced yes)
		(effects
			(font
				(size 1.27 1.27)
			)
			(justify right)
		)
		(property "Intersheetrefs" "${INTERSHEET_REFS}"
			(at 5.715 317.5 0)
			(effects
				(font
					(size 1.27 1.27)
				)
				(hide yes)
			)
		)
	)
	(global_label "SPI0_MOSI"
		(shape input)
		(at 193.04 262.89 180)
		(fields_autoplaced yes)
		(effects
			(font
				(size 1.27 1.27)
			)
			(justify right)
		)
		(property "Intersheetrefs" "${INTERSHEET_REFS}"
			(at -24.765 3.175 0)
			(effects
				(font
					(size 1.27 1.27)
				)
				(hide yes)
			)
		)
	)
	(global_label "VCC3V3"
		(shape input)
		(at 241.3 50.8 0)
		(fields_autoplaced yes)
		(effects
			(font
				(size 1.27 1.27)
			)
			(justify left)
		)
		(property "Intersheetrefs" "${INTERSHEET_REFS}"
			(at 354.965 11.43 0)
			(effects
				(font
					(size 1.27 1.27)
				)
				(hide yes)
			)
		)
	)
	(global_label "ULPI2_NXT"
		(shape input)
		(at 383.54 167.64 0)
		(fields_autoplaced yes)
		(effects
			(font
				(size 1.27 1.27)
			)
			(justify left)
		)
		(property "Intersheetrefs" "${INTERSHEET_REFS}"
			(at 23.495 -52.705 0)
			(effects
				(font
					(size 1.27 1.27)
				)
				(hide yes)
			)
		)
	)
	(global_label "PCIE_BMC_RX_P"
		(shape input)
		(at 48.26 74.93 180)
		(fields_autoplaced yes)
		(effects
			(font
				(size 1.27 1.27)
			)
			(justify right)
		)
		(property "Intersheetrefs" "${INTERSHEET_REFS}"
			(at 3.81 17.145 0)
			(effects
				(font
					(size 1.27 1.27)
				)
				(hide yes)
			)
		)
	)
	(global_label "VCC1V0"
		(shape input)
		(at 25.4 36.83 180)
		(fields_autoplaced yes)
		(effects
			(font
				(size 1.27 1.27)
			)
			(justify right)
		)
		(property "Intersheetrefs" "${INTERSHEET_REFS}"
			(at 15.9396 36.9094 0)
			(effects
				(font
					(size 1.27 1.27)
				)
				(justify right)
				(hide yes)
			)
		)
	)
	(global_label "ESPI_IO1"
		(shape input)
		(at 208.28 186.69 0)
		(fields_autoplaced yes)
		(effects
			(font
				(size 1.27 1.27)
			)
			(justify left)
		)
		(property "Intersheetrefs" "${INTERSHEET_REFS}"
			(at -6.985 0 0)
			(effects
				(font
					(size 1.27 1.27)
				)
				(hide yes)
			)
		)
	)
	(global_label "I3C[0]_SCL"
		(shape input)
		(at 123.19 190.5 0)
		(fields_autoplaced yes)
		(effects
			(font
				(size 1.27 1.27)
			)
			(justify left)
		)
		(property "Intersheetrefs" "${INTERSHEET_REFS}"
			(at -6.35 13.97 0)
			(effects
				(font
					(size 1.27 1.27)
				)
				(hide yes)
			)
		)
	)
	(global_label "I3C[3]_SDA_3V3"
		(shape input)
		(at 31.75 208.28 180)
		(fields_autoplaced yes)
		(effects
			(font
				(size 1.27 1.27)
			)
			(justify right)
		)
		(property "Intersheetrefs" "${INTERSHEET_REFS}"
			(at -8.89 -2.54 0)
			(effects
				(font
					(size 1.27 1.27)
				)
				(justify right)
				(hide yes)
			)
		)
	)
	(global_label "MMC_RSTN"
		(shape input)
		(at 147.32 255.27 0)
		(fields_autoplaced yes)
		(effects
			(font
				(size 1.27 1.27)
			)
			(justify left)
		)
		(property "Intersheetrefs" "${INTERSHEET_REFS}"
			(at -22.225 3.81 0)
			(effects
				(font
					(size 1.27 1.27)
				)
				(hide yes)
			)
		)
	)
	(global_label "ESPI_CS0_N_1V8"
		(shape input)
		(at 186.69 176.53 180)
		(fields_autoplaced yes)
		(effects
			(font
				(size 1.27 1.27)
			)
			(justify right)
		)
		(property "Intersheetrefs" "${INTERSHEET_REFS}"
			(at -4.445 0 0)
			(effects
				(font
					(size 1.27 1.27)
				)
				(hide yes)
			)
		)
	)
	(global_label "PCIE_BMC_CLK_100_P"
		(shape input)
		(at 54.61 96.52 180)
		(fields_autoplaced yes)
		(effects
			(font
				(size 1.27 1.27)
			)
			(justify right)
		)
		(property "Intersheetrefs" "${INTERSHEET_REFS}"
			(at 3.81 15.875 0)
			(effects
				(font
					(size 1.27 1.27)
				)
				(hide yes)
			)
		)
	)
	(global_label "ESPI_ALERT_N"
		(shape input)
		(at 208.28 179.07 0)
		(fields_autoplaced yes)
		(effects
			(font
				(size 1.27 1.27)
			)
			(justify left)
		)
		(property "Intersheetrefs" "${INTERSHEET_REFS}"
			(at -6.985 0 0)
			(effects
				(font
					(size 1.27 1.27)
				)
				(hide yes)
			)
		)
	)
	(global_label "MMC_DAT3"
		(shape input)
		(at 147.32 267.97 0)
		(fields_autoplaced yes)
		(effects
			(font
				(size 1.27 1.27)
			)
			(justify left)
		)
		(property "Intersheetrefs" "${INTERSHEET_REFS}"
			(at -22.225 3.81 0)
			(effects
				(font
					(size 1.27 1.27)
				)
				(hide yes)
			)
		)
	)
	(global_label "I3C[1]_SCL_3V3"
		(shape input)
		(at 31.75 195.58 180)
		(fields_autoplaced yes)
		(effects
			(font
				(size 1.27 1.27)
			)
			(justify right)
		)
		(property "Intersheetrefs" "${INTERSHEET_REFS}"
			(at -8.89 -7.62 0)
			(effects
				(font
					(size 1.27 1.27)
				)
				(justify right)
				(hide yes)
			)
		)
	)
	(global_label "ULPI1_DATA5"
		(shape input)
		(at 383.54 66.04 0)
		(fields_autoplaced yes)
		(effects
			(font
				(size 1.27 1.27)
			)
			(justify left)
		)
		(property "Intersheetrefs" "${INTERSHEET_REFS}"
			(at 15.24 160.02 0)
			(effects
				(font
					(size 1.27 1.27)
				)
				(hide yes)
			)
		)
	)
	(global_label "MMC_DAT1"
		(shape input)
		(at 147.32 262.89 0)
		(fields_autoplaced yes)
		(effects
			(font
				(size 1.27 1.27)
			)
			(justify left)
		)
		(property "Intersheetrefs" "${INTERSHEET_REFS}"
			(at -22.225 3.81 0)
			(effects
				(font
					(size 1.27 1.27)
				)
				(hide yes)
			)
		)
	)
	(global_label "MMC_DAT4"
		(shape input)
		(at 147.32 270.51 0)
		(fields_autoplaced yes)
		(effects
			(font
				(size 1.27 1.27)
			)
			(justify left)
		)
		(property "Intersheetrefs" "${INTERSHEET_REFS}"
			(at -22.225 3.81 0)
			(effects
				(font
					(size 1.27 1.27)
				)
				(hide yes)
			)
		)
	)
	(global_label "ULPI2_STP"
		(shape output)
		(at 383.54 172.72 0)
		(fields_autoplaced yes)
		(effects
			(font
				(size 1.27 1.27)
			)
			(justify left)
		)
		(property "Intersheetrefs" "${INTERSHEET_REFS}"
			(at 395.7218 172.6406 0)
			(effects
				(font
					(size 1.27 1.27)
				)
				(justify left)
				(hide yes)
			)
		)
	)
	(global_label "I3C[1]_SCL"
		(shape input)
		(at 123.19 195.58 0)
		(fields_autoplaced yes)
		(effects
			(font
				(size 1.27 1.27)
			)
			(justify left)
		)
		(property "Intersheetrefs" "${INTERSHEET_REFS}"
			(at -6.35 13.97 0)
			(effects
				(font
					(size 1.27 1.27)
				)
				(hide yes)
			)
		)
	)
	(global_label "ESPI_IO3"
		(shape input)
		(at 208.28 191.77 0)
		(fields_autoplaced yes)
		(effects
			(font
				(size 1.27 1.27)
			)
			(justify left)
		)
		(property "Intersheetrefs" "${INTERSHEET_REFS}"
			(at -6.985 0 0)
			(effects
				(font
					(size 1.27 1.27)
				)
				(hide yes)
			)
		)
	)
	(global_label "I3C[3]_SCL_3V3"
		(shape input)
		(at 31.75 205.74 180)
		(fields_autoplaced yes)
		(effects
			(font
				(size 1.27 1.27)
			)
			(justify right)
		)
		(property "Intersheetrefs" "${INTERSHEET_REFS}"
			(at -8.89 -7.62 0)
			(effects
				(font
					(size 1.27 1.27)
				)
				(justify right)
				(hide yes)
			)
		)
	)
	(global_label "ULPI1_DIR"
		(shape output)
		(at 383.54 78.74 0)
		(fields_autoplaced yes)
		(effects
			(font
				(size 1.27 1.27)
			)
			(justify left)
		)
		(property "Intersheetrefs" "${INTERSHEET_REFS}"
			(at 395.4194 78.6606 0)
			(effects
				(font
					(size 1.27 1.27)
				)
				(justify left)
				(hide yes)
			)
		)
	)
	(global_label "VCC3V3"
		(shape input)
		(at 31.75 172.72 180)
		(fields_autoplaced yes)
		(effects
			(font
				(size 1.27 1.27)
			)
			(justify right)
		)
		(property "Intersheetrefs" "${INTERSHEET_REFS}"
			(at -0.635 -0.635 0)
			(effects
				(font
					(size 1.27 1.27)
				)
				(justify right)
				(hide yes)
			)
		)
	)
	(global_label "PCIE_BMC_RX_N"
		(shape input)
		(at 48.26 77.47 180)
		(fields_autoplaced yes)
		(effects
			(font
				(size 1.27 1.27)
			)
			(justify right)
		)
		(property "Intersheetrefs" "${INTERSHEET_REFS}"
			(at 3.81 17.145 0)
			(effects
				(font
					(size 1.27 1.27)
				)
				(hide yes)
			)
		)
	)
	(global_label "JTAG_TCK"
		(shape output)
		(at 275.59 31.75 0)
		(fields_autoplaced yes)
		(effects
			(font
				(size 1.27 1.27)
			)
			(justify left)
		)
		(property "Intersheetrefs" "${INTERSHEET_REFS}"
			(at 286.6832 31.6706 0)
			(effects
				(font
					(size 1.27 1.27)
				)
				(justify left)
				(hide yes)
			)
		)
	)
	(global_label "VCC3V3"
		(shape input)
		(at 306.07 38.1 180)
		(fields_autoplaced yes)
		(effects
			(font
				(size 1.27 1.27)
			)
			(justify right)
		)
		(property "Intersheetrefs" "${INTERSHEET_REFS}"
			(at 280.67 397.51 0)
			(effects
				(font
					(size 1.27 1.27)
				)
				(hide yes)
			)
		)
	)
	(global_label "ESPI_IO1_1V8"
		(shape input)
		(at 186.69 186.69 180)
		(fields_autoplaced yes)
		(effects
			(font
				(size 1.27 1.27)
			)
			(justify right)
		)
		(property "Intersheetrefs" "${INTERSHEET_REFS}"
			(at -4.445 0 0)
			(effects
				(font
					(size 1.27 1.27)
				)
				(hide yes)
			)
		)
	)
	(global_label "MMC_DAT0"
		(shape input)
		(at 147.32 260.35 0)
		(fields_autoplaced yes)
		(effects
			(font
				(size 1.27 1.27)
			)
			(justify left)
		)
		(property "Intersheetrefs" "${INTERSHEET_REFS}"
			(at -22.225 3.81 0)
			(effects
				(font
					(size 1.27 1.27)
				)
				(hide yes)
			)
		)
	)
	(global_label "ESPI_IO0"
		(shape input)
		(at 208.28 184.15 0)
		(fields_autoplaced yes)
		(effects
			(font
				(size 1.27 1.27)
			)
			(justify left)
		)
		(property "Intersheetrefs" "${INTERSHEET_REFS}"
			(at -6.985 0 0)
			(effects
				(font
					(size 1.27 1.27)
				)
				(hide yes)
			)
		)
	)
	(global_label "USB2_D_P"
		(shape input)
		(at 342.9 147.32 180)
		(fields_autoplaced yes)
		(effects
			(font
				(size 1.27 1.27)
			)
			(justify right)
		)
		(property "Intersheetrefs" "${INTERSHEET_REFS}"
			(at 43.18 -51.435 0)
			(effects
				(font
					(size 1.27 1.27)
				)
				(hide yes)
			)
		)
	)
	(global_label "MMC_DAT7"
		(shape input)
		(at 147.32 278.13 0)
		(fields_autoplaced yes)
		(effects
			(font
				(size 1.27 1.27)
			)
			(justify left)
		)
		(property "Intersheetrefs" "${INTERSHEET_REFS}"
			(at -22.225 3.81 0)
			(effects
				(font
					(size 1.27 1.27)
				)
				(hide yes)
			)
		)
	)
	(global_label "VCC3V3"
		(shape input)
		(at 231.14 158.75 0)
		(fields_autoplaced yes)
		(effects
			(font
				(size 1.27 1.27)
			)
			(justify left)
		)
		(property "Intersheetrefs" "${INTERSHEET_REFS}"
			(at 394.335 -10.795 0)
			(effects
				(font
					(size 1.27 1.27)
				)
				(hide yes)
			)
		)
	)
	(global_label "ESPI_ALERT_N_1V8"
		(shape input)
		(at 186.69 179.07 180)
		(fields_autoplaced yes)
		(effects
			(font
				(size 1.27 1.27)
			)
			(justify right)
		)
		(property "Intersheetrefs" "${INTERSHEET_REFS}"
			(at -4.445 0 0)
			(effects
				(font
					(size 1.27 1.27)
				)
				(hide yes)
			)
		)
	)
	(global_label "ESPI_CS1_N_1V8"
		(shape input)
		(at 186.69 223.52 180)
		(fields_autoplaced yes)
		(effects
			(font
				(size 1.27 1.27)
			)
			(justify right)
		)
		(property "Intersheetrefs" "${INTERSHEET_REFS}"
			(at -6.35 6.985 0)
			(effects
				(font
					(size 1.27 1.27)
				)
				(hide yes)
			)
		)
	)
	(global_label "ESPI_IO2"
		(shape input)
		(at 208.28 189.23 0)
		(fields_autoplaced yes)
		(effects
			(font
				(size 1.27 1.27)
			)
			(justify left)
		)
		(property "Intersheetrefs" "${INTERSHEET_REFS}"
			(at -6.985 0 0)
			(effects
				(font
					(size 1.27 1.27)
				)
				(hide yes)
			)
		)
	)
	(global_label "DBG_UART_TX"
		(shape input)
		(at 275.59 88.9 0)
		(fields_autoplaced yes)
		(effects
			(font
				(size 1.27 1.27)
			)
			(justify left)
		)
		(property "Intersheetrefs" "${INTERSHEET_REFS}"
			(at 43.18 9.525 0)
			(effects
				(font
					(size 1.27 1.27)
				)
				(hide yes)
			)
		)
	)
	(global_label "MMC_CLK"
		(shape input)
		(at 147.32 252.73 0)
		(fields_autoplaced yes)
		(effects
			(font
				(size 1.27 1.27)
			)
			(justify left)
		)
		(property "Intersheetrefs" "${INTERSHEET_REFS}"
			(at -22.225 3.81 0)
			(effects
				(font
					(size 1.27 1.27)
				)
				(hide yes)
			)
		)
	)
	(global_label "SPI0_MISO"
		(shape input)
		(at 193.04 265.43 180)
		(fields_autoplaced yes)
		(effects
			(font
				(size 1.27 1.27)
			)
			(justify right)
		)
		(property "Intersheetrefs" "${INTERSHEET_REFS}"
			(at -24.765 3.175 0)
			(effects
				(font
					(size 1.27 1.27)
				)
				(hide yes)
			)
		)
	)
	(global_label "I3C[3]_SDA"
		(shape input)
		(at 123.19 208.28 0)
		(fields_autoplaced yes)
		(effects
			(font
				(size 1.27 1.27)
			)
			(justify left)
		)
		(property "Intersheetrefs" "${INTERSHEET_REFS}"
			(at -6.35 13.97 0)
			(effects
				(font
					(size 1.27 1.27)
				)
				(hide yes)
			)
		)
	)
	(global_label "ULPI2_CLKOUT"
		(shape output)
		(at 383.54 175.26 0)
		(fields_autoplaced yes)
		(effects
			(font
				(size 1.27 1.27)
			)
			(justify left)
		)
		(property "Intersheetrefs" "${INTERSHEET_REFS}"
			(at 399.4713 175.1806 0)
			(effects
				(font
					(size 1.27 1.27)
				)
				(justify left)
				(hide yes)
			)
		)
	)
	(global_label "VCC5V0"
		(shape input)
		(at 342.9 154.94 180)
		(fields_autoplaced yes)
		(effects
			(font
				(size 1.27 1.27)
			)
			(justify right)
		)
		(property "Intersheetrefs" "${INTERSHEET_REFS}"
			(at 165.735 444.5 0)
			(effects
				(font
					(size 1.27 1.27)
				)
				(hide yes)
			)
		)
	)
	(global_label "1V8_FT"
		(shape input)
		(at 143.51 54.61 180)
		(fields_autoplaced yes)
		(effects
			(font
				(size 1.27 1.27)
			)
			(justify right)
		)
		(property "Intersheetrefs" "${INTERSHEET_REFS}"
			(at 25.4 146.685 0)
			(effects
				(font
					(size 1.27 1.27)
				)
				(hide yes)
			)
		)
	)
	(global_label "ULPI1_DATA1"
		(shape input)
		(at 383.54 55.88 0)
		(fields_autoplaced yes)
		(effects
			(font
				(size 1.27 1.27)
			)
			(justify left)
		)
		(property "Intersheetrefs" "${INTERSHEET_REFS}"
			(at 15.24 160.02 0)
			(effects
				(font
					(size 1.27 1.27)
				)
				(hide yes)
			)
		)
	)
	(global_label "ULPI1_RESET"
		(shape input)
		(at 383.54 86.36 0)
		(fields_autoplaced yes)
		(effects
			(font
				(size 1.27 1.27)
			)
			(justify left)
		)
		(property "Intersheetrefs" "${INTERSHEET_REFS}"
			(at 15.24 -33.02 0)
			(effects
				(font
					(size 1.27 1.27)
				)
				(hide yes)
			)
		)
	)
	(global_label "ESPI_RESET_N_1V8"
		(shape input)
		(at 186.69 181.61 180)
		(fields_autoplaced yes)
		(effects
			(font
				(size 1.27 1.27)
			)
			(justify right)
		)
		(property "Intersheetrefs" "${INTERSHEET_REFS}"
			(at -4.445 0 0)
			(effects
				(font
					(size 1.27 1.27)
				)
				(hide yes)
			)
		)
	)
	(global_label "ULPI2_DATA4"
		(shape input)
		(at 383.54 154.94 0)
		(fields_autoplaced yes)
		(effects
			(font
				(size 1.27 1.27)
			)
			(justify left)
		)
		(property "Intersheetrefs" "${INTERSHEET_REFS}"
			(at 23.495 362.585 0)
			(effects
				(font
					(size 1.27 1.27)
				)
				(hide yes)
			)
		)
	)
	(global_label "DBG_UART_RX"
		(shape input)
		(at 275.59 86.36 0)
		(fields_autoplaced yes)
		(effects
			(font
				(size 1.27 1.27)
			)
			(justify left)
		)
		(property "Intersheetrefs" "${INTERSHEET_REFS}"
			(at 43.18 9.525 0)
			(effects
				(font
					(size 1.27 1.27)
				)
				(hide yes)
			)
		)
	)
	(global_label "ULPI2_DATA0"
		(shape input)
		(at 383.54 144.78 0)
		(fields_autoplaced yes)
		(effects
			(font
				(size 1.27 1.27)
			)
			(justify left)
		)
		(property "Intersheetrefs" "${INTERSHEET_REFS}"
			(at 23.495 362.585 0)
			(effects
				(font
					(size 1.27 1.27)
				)
				(hide yes)
			)
		)
	)
	(global_label "ULPI1_DATA0"
		(shape input)
		(at 383.54 53.34 0)
		(fields_autoplaced yes)
		(effects
			(font
				(size 1.27 1.27)
			)
			(justify left)
		)
		(property "Intersheetrefs" "${INTERSHEET_REFS}"
			(at 15.24 160.02 0)
			(effects
				(font
					(size 1.27 1.27)
				)
				(hide yes)
			)
		)
	)
	(global_label "ULPI2_DATA6"
		(shape input)
		(at 383.54 160.02 0)
		(fields_autoplaced yes)
		(effects
			(font
				(size 1.27 1.27)
			)
			(justify left)
		)
		(property "Intersheetrefs" "${INTERSHEET_REFS}"
			(at 23.495 362.585 0)
			(effects
				(font
					(size 1.27 1.27)
				)
				(hide yes)
			)
		)
	)
	(global_label "ULPI1_NXT"
		(shape output)
		(at 383.54 76.2 0)
		(fields_autoplaced yes)
		(effects
			(font
				(size 1.27 1.27)
			)
			(justify left)
		)
		(property "Intersheetrefs" "${INTERSHEET_REFS}"
			(at 395.7823 76.1206 0)
			(effects
				(font
					(size 1.27 1.27)
				)
				(justify left)
				(hide yes)
			)
		)
	)
	(global_label "MMC_DAT2"
		(shape input)
		(at 147.32 265.43 0)
		(fields_autoplaced yes)
		(effects
			(font
				(size 1.27 1.27)
			)
			(justify left)
		)
		(property "Intersheetrefs" "${INTERSHEET_REFS}"
			(at -22.225 3.81 0)
			(effects
				(font
					(size 1.27 1.27)
				)
				(hide yes)
			)
		)
	)
	(global_label "SPI0_CLK"
		(shape input)
		(at 193.04 267.97 180)
		(fields_autoplaced yes)
		(effects
			(font
				(size 1.27 1.27)
			)
			(justify right)
		)
		(property "Intersheetrefs" "${INTERSHEET_REFS}"
			(at -24.765 3.175 0)
			(effects
				(font
					(size 1.27 1.27)
				)
				(hide yes)
			)
		)
	)
	(global_label "ESPI_CLK_1V8"
		(shape input)
		(at 186.69 173.99 180)
		(fields_autoplaced yes)
		(effects
			(font
				(size 1.27 1.27)
			)
			(justify right)
		)
		(property "Intersheetrefs" "${INTERSHEET_REFS}"
			(at -4.445 0 0)
			(effects
				(font
					(size 1.27 1.27)
				)
				(hide yes)
			)
		)
	)
	(global_label "VCC3V3"
		(shape input)
		(at 311.15 173.99 180)
		(fields_autoplaced yes)
		(effects
			(font
				(size 1.27 1.27)
			)
			(justify right)
		)
		(property "Intersheetrefs" "${INTERSHEET_REFS}"
			(at 213.36 422.275 0)
			(effects
				(font
					(size 1.27 1.27)
				)
				(hide yes)
			)
		)
	)
	(global_label "VCC1V0"
		(shape input)
		(at 127 172.72 0)
		(fields_autoplaced yes)
		(effects
			(font
				(size 1.27 1.27)
			)
			(justify left)
		)
		(property "Intersheetrefs" "${INTERSHEET_REFS}"
			(at -2.54 0 0)
			(effects
				(font
					(size 1.27 1.27)
				)
				(hide yes)
			)
		)
	)
	(global_label "I3C[1]_SDA_3V3"
		(shape input)
		(at 31.75 198.12 180)
		(fields_autoplaced yes)
		(effects
			(font
				(size 1.27 1.27)
			)
			(justify right)
		)
		(property "Intersheetrefs" "${INTERSHEET_REFS}"
			(at -8.89 -2.54 0)
			(effects
				(font
					(size 1.27 1.27)
				)
				(justify right)
				(hide yes)
			)
		)
	)
	(global_label "ULPI2_DATA5"
		(shape input)
		(at 383.54 157.48 0)
		(fields_autoplaced yes)
		(effects
			(font
				(size 1.27 1.27)
			)
			(justify left)
		)
		(property "Intersheetrefs" "${INTERSHEET_REFS}"
			(at 23.495 362.585 0)
			(effects
				(font
					(size 1.27 1.27)
				)
				(hide yes)
			)
		)
	)
	(global_label "I3C[2]_SCL_3V3"
		(shape input)
		(at 31.75 200.66 180)
		(fields_autoplaced yes)
		(effects
			(font
				(size 1.27 1.27)
			)
			(justify right)
		)
		(property "Intersheetrefs" "${INTERSHEET_REFS}"
			(at -8.89 -7.62 0)
			(effects
				(font
					(size 1.27 1.27)
				)
				(justify right)
				(hide yes)
			)
		)
	)
	(global_label "VCC3V3"
		(shape input)
		(at 231.14 207.01 0)
		(fields_autoplaced yes)
		(effects
			(font
				(size 1.27 1.27)
			)
			(justify left)
		)
		(property "Intersheetrefs" "${INTERSHEET_REFS}"
			(at 424.18 418.465 0)
			(effects
				(font
					(size 1.27 1.27)
				)
				(hide yes)
			)
		)
	)
	(global_label "I3C[2]_SDA"
		(shape input)
		(at 123.19 203.2 0)
		(fields_autoplaced yes)
		(effects
			(font
				(size 1.27 1.27)
			)
			(justify left)
		)
		(property "Intersheetrefs" "${INTERSHEET_REFS}"
			(at -6.35 13.97 0)
			(effects
				(font
					(size 1.27 1.27)
				)
				(hide yes)
			)
		)
	)
	(global_label "VCC1V2"
		(shape input)
		(at 25.4 21.59 180)
		(fields_autoplaced yes)
		(effects
			(font
				(size 1.27 1.27)
			)
			(justify right)
		)
		(property "Intersheetrefs" "${INTERSHEET_REFS}"
			(at 15.9396 21.6694 0)
			(effects
				(font
					(size 1.27 1.27)
				)
				(justify right)
				(hide yes)
			)
		)
	)
	(global_label "ULPI2_DATA7"
		(shape input)
		(at 383.54 162.56 0)
		(fields_autoplaced yes)
		(effects
			(font
				(size 1.27 1.27)
			)
			(justify left)
		)
		(property "Intersheetrefs" "${INTERSHEET_REFS}"
			(at 23.495 362.585 0)
			(effects
				(font
					(size 1.27 1.27)
				)
				(hide yes)
			)
		)
	)
	(symbol
		(lib_id "antmicroInterfaceControllers:USB3300-EZK-TR")
		(at 358.14 45.72 0)
		(unit 1)
		(exclude_from_sim no)
		(in_bom yes)
		(on_board yes)
		(dnp no)
		(fields_autoplaced yes)
		(property "Reference" "U17"
			(at 370.205 37.465 0)
			(effects
				(font
					(size 1.27 1.27)
				)
			)
		)
		(property "Value" "USB3300-EZK-TR"
			(at 370.205 40.005 0)
			(effects
				(font
					(size 1.27 1.27)
				)
			)
		)
		(property "Footprint" "antmicro-footprints:QFN-32-1EP_5x5mm"
			(at 396.24 53.34 0)
			(effects
				(font
					(size 1.27 1.27)
					(thickness 0.15)
				)
				(justify left bottom)
				(hide yes)
			)
		)
		(property "Datasheet" "https://ww1.microchip.com/downloads/en/DeviceDoc/00001783C.pdf"
			(at 396.24 55.88 0)
			(effects
				(font
					(size 1.27 1.27)
					(thickness 0.15)
				)
				(justify left bottom)
				(hide yes)
			)
		)
		(property "Description" "USB Interface, USB Host Controller, USB 2.0 OTG, 3 V, 3.6 V, VQFN, 32 Pins"
			(at 358.14 45.72 0)
			(effects
				(font
					(size 1.27 1.27)
				)
				(hide yes)
			)
		)
		(property "Manufacturer" "Microchip Technology"
			(at 396.24 58.42 0)
			(effects
				(font
					(size 1.27 1.27)
					(thickness 0.15)
				)
				(justify left bottom)
				(hide yes)
			)
		)
		(property "MPN" "USB3300-EZK-TR"
			(at 396.24 60.96 0)
			(effects
				(font
					(size 1.27 1.27)
					(thickness 0.15)
				)
				(justify left bottom)
				(hide yes)
			)
		)
		(property "Author" "Antmicro"
			(at 396.24 63.5 0)
			(effects
				(font
					(size 1.27 1.27)
					(thickness 0.15)
				)
				(justify left bottom)
				(hide yes)
			)
		)
		(property "License" "Apache-2.0"
			(at 396.24 66.04 0)
			(effects
				(font
					(size 1.27 1.27)
					(thickness 0.15)
				)
				(justify left bottom)
				(hide yes)
			)
		)
		(pin "1"
		)
		(pin "10"
		)
		(pin "11"
		)
		(pin "12"
		)
		(pin "13"
		)
		(pin "14"
		)
		(pin "15"
		)
		(pin "16"
		)
		(pin "17"
		)
		(pin "18"
		)
		(pin "19"
		)
		(pin "2"
		)
		(pin "20"
		)
		(pin "21"
		)
		(pin "22"
		)
		(pin "23"
		)
		(pin "24"
		)
		(pin "25"
		)
		(pin "26"
		)
		(pin "27"
		)
		(pin "28"
		)
		(pin "29"
		)
		(pin "3"
		)
		(pin "30"
		)
		(pin "31"
		)
		(pin "32"
		)
		(pin "33"
		)
		(pin "4"
		)
		(pin "5"
		)
		(pin "6"
		)
		(pin "7"
		)
		(pin "8"
		)
		(pin "9"
		)
		(instances
			(project "artix-dc-scm"
				(path ""
					(reference "U17")
					(unit 1)
				)
			)
		)
	)
	(symbol
		(lib_id "antmicroCapacitors0402:C_2u2_0402")
		(at 27.94 236.22 90)
		(unit 1)
		(exclude_from_sim no)
		(in_bom yes)
		(on_board yes)
		(dnp no)
		(property "Reference" "C183"
			(at 28.575 231.775 90)
			(effects
				(font
					(size 1.27 1.27)
				)
				(justify right)
			)
		)
		(property "Value" "C_2u2_0402"
			(at 38.1 215.9 0)
			(effects
				(font
					(size 1.27 1.27)
					(thickness 0.15)
				)
				(justify left bottom)
				(hide yes)
			)
		)
		(property "Footprint" "antmicro-footprints:C_0402_1005Metric"
			(at 40.64 215.9 0)
			(effects
				(font
					(size 1.27 1.27)
					(thickness 0.15)
				)
				(justify left bottom)
				(hide yes)
			)
		)
		(property "Datasheet" "https://product.tdk.com/en/search/capacitor/ceramic/mlcc/info?part_no=C1005X5R1A225K050BC"
			(at 43.18 215.9 0)
			(effects
				(font
					(size 1.27 1.27)
					(thickness 0.15)
				)
				(justify left bottom)
				(hide yes)
			)
		)
		(property "Description" "SMD Multilayer Ceramic Capacitor, 2.2 µF, 10 V, 0402 [1005 Metric], ± 10%, X5R, C"
			(at 27.94 236.22 0)
			(effects
				(font
					(size 1.27 1.27)
				)
				(hide yes)
			)
		)
		(property "Manufacturer" "TDK"
			(at 48.26 215.9 0)
			(effects
				(font
					(size 1.27 1.27)
					(thickness 0.15)
				)
				(justify left bottom)
				(hide yes)
			)
		)
		(property "MPN" "C1005X5R1A225K050BC"
			(at 45.72 215.9 0)
			(effects
				(font
					(size 1.27 1.27)
					(thickness 0.15)
				)
				(justify left bottom)
				(hide yes)
			)
		)
		(property "Val" "2u2"
			(at 28.575 235.585 90)
			(effects
				(font
					(size 1.27 1.27)
					(thickness 0.15)
				)
				(justify right)
			)
		)
		(property "License" "Apache-2.0"
			(at 50.8 215.9 0)
			(effects
				(font
					(size 1.27 1.27)
					(thickness 0.15)
				)
				(justify left bottom)
				(hide yes)
			)
		)
		(property "Author" "Antmicro"
			(at 53.34 215.9 0)
			(effects
				(font
					(size 1.27 1.27)
					(thickness 0.15)
				)
				(justify left bottom)
				(hide yes)
			)
		)
		(property "Voltage" ""
			(at 55.88 215.9 0)
			(effects
				(font
					(size 1.27 1.27)
				)
				(justify left bottom)
				(hide yes)
			)
		)
		(property "Dielectric" ""
			(at 58.42 215.9 0)
			(effects
				(font
					(size 1.27 1.27)
				)
				(justify left bottom)
				(hide yes)
			)
		)
		(pin "1"
		)
		(pin "2"
		)
		(instances
			(project "artix-dc-scm"
				(path ""
					(reference "C183")
					(unit 1)
				)
			)
		)
	)
	(symbol
		(lib_id "antmicroCapacitors0402:C_2u2_0402")
		(at 35.56 236.22 90)
		(unit 1)
		(exclude_from_sim no)
		(in_bom yes)
		(on_board yes)
		(dnp no)
		(property "Reference" "C184"
			(at 36.195 231.775 90)
			(effects
				(font
					(size 1.27 1.27)
				)
				(justify right)
			)
		)
		(property "Value" "C_2u2_0402"
			(at 45.72 215.9 0)
			(effects
				(font
					(size 1.27 1.27)
					(thickness 0.15)
				)
				(justify left bottom)
				(hide yes)
			)
		)
		(property "Footprint" "antmicro-footprints:C_0402_1005Metric"
			(at 48.26 215.9 0)
			(effects
				(font
					(size 1.27 1.27)
					(thickness 0.15)
				)
				(justify left bottom)
				(hide yes)
			)
		)
		(property "Datasheet" "https://product.tdk.com/en/search/capacitor/ceramic/mlcc/info?part_no=C1005X5R1A225K050BC"
			(at 50.8 215.9 0)
			(effects
				(font
					(size 1.27 1.27)
					(thickness 0.15)
				)
				(justify left bottom)
				(hide yes)
			)
		)
		(property "Description" "SMD Multilayer Ceramic Capacitor, 2.2 µF, 10 V, 0402 [1005 Metric], ± 10%, X5R, C"
			(at 35.56 236.22 0)
			(effects
				(font
					(size 1.27 1.27)
				)
				(hide yes)
			)
		)
		(property "Manufacturer" "TDK"
			(at 55.88 215.9 0)
			(effects
				(font
					(size 1.27 1.27)
					(thickness 0.15)
				)
				(justify left bottom)
				(hide yes)
			)
		)
		(property "MPN" "C1005X5R1A225K050BC"
			(at 53.34 215.9 0)
			(effects
				(font
					(size 1.27 1.27)
					(thickness 0.15)
				)
				(justify left bottom)
				(hide yes)
			)
		)
		(property "Val" "2u2"
			(at 36.195 235.585 90)
			(effects
				(font
					(size 1.27 1.27)
					(thickness 0.15)
				)
				(justify right)
			)
		)
		(property "License" "Apache-2.0"
			(at 58.42 215.9 0)
			(effects
				(font
					(size 1.27 1.27)
					(thickness 0.15)
				)
				(justify left bottom)
				(hide yes)
			)
		)
		(property "Author" "Antmicro"
			(at 60.96 215.9 0)
			(effects
				(font
					(size 1.27 1.27)
					(thickness 0.15)
				)
				(justify left bottom)
				(hide yes)
			)
		)
		(property "Voltage" ""
			(at 63.5 215.9 0)
			(effects
				(font
					(size 1.27 1.27)
				)
				(justify left bottom)
				(hide yes)
			)
		)
		(property "Dielectric" ""
			(at 66.04 215.9 0)
			(effects
				(font
					(size 1.27 1.27)
				)
				(justify left bottom)
				(hide yes)
			)
		)
		(pin "1"
		)
		(pin "2"
		)
		(instances
			(project "artix-dc-scm"
				(path ""
					(reference "C184")
					(unit 1)
				)
			)
		)
	)
	(symbol
		(lib_id "antmicroCapacitors0402:C_2u2_0402")
		(at 43.18 236.22 90)
		(unit 1)
		(exclude_from_sim no)
		(in_bom yes)
		(on_board yes)
		(dnp no)
		(property "Reference" "C185"
			(at 43.815 231.775 90)
			(effects
				(font
					(size 1.27 1.27)
				)
				(justify right)
			)
		)
		(property "Value" "C_2u2_0402"
			(at 53.34 215.9 0)
			(effects
				(font
					(size 1.27 1.27)
					(thickness 0.15)
				)
				(justify left bottom)
				(hide yes)
			)
		)
		(property "Footprint" "antmicro-footprints:C_0402_1005Metric"
			(at 55.88 215.9 0)
			(effects
				(font
					(size 1.27 1.27)
					(thickness 0.15)
				)
				(justify left bottom)
				(hide yes)
			)
		)
		(property "Datasheet" "https://product.tdk.com/en/search/capacitor/ceramic/mlcc/info?part_no=C1005X5R1A225K050BC"
			(at 58.42 215.9 0)
			(effects
				(font
					(size 1.27 1.27)
					(thickness 0.15)
				)
				(justify left bottom)
				(hide yes)
			)
		)
		(property "Description" "SMD Multilayer Ceramic Capacitor, 2.2 µF, 10 V, 0402 [1005 Metric], ± 10%, X5R, C"
			(at 43.18 236.22 0)
			(effects
				(font
					(size 1.27 1.27)
				)
				(hide yes)
			)
		)
		(property "Manufacturer" "TDK"
			(at 63.5 215.9 0)
			(effects
				(font
					(size 1.27 1.27)
					(thickness 0.15)
				)
				(justify left bottom)
				(hide yes)
			)
		)
		(property "MPN" "C1005X5R1A225K050BC"
			(at 60.96 215.9 0)
			(effects
				(font
					(size 1.27 1.27)
					(thickness 0.15)
				)
				(justify left bottom)
				(hide yes)
			)
		)
		(property "Val" "2u2"
			(at 43.815 235.585 90)
			(effects
				(font
					(size 1.27 1.27)
					(thickness 0.15)
				)
				(justify right)
			)
		)
		(property "License" "Apache-2.0"
			(at 66.04 215.9 0)
			(effects
				(font
					(size 1.27 1.27)
					(thickness 0.15)
				)
				(justify left bottom)
				(hide yes)
			)
		)
		(property "Author" "Antmicro"
			(at 68.58 215.9 0)
			(effects
				(font
					(size 1.27 1.27)
					(thickness 0.15)
				)
				(justify left bottom)
				(hide yes)
			)
		)
		(property "Voltage" ""
			(at 71.12 215.9 0)
			(effects
				(font
					(size 1.27 1.27)
				)
				(justify left bottom)
				(hide yes)
			)
		)
		(property "Dielectric" ""
			(at 73.66 215.9 0)
			(effects
				(font
					(size 1.27 1.27)
				)
				(justify left bottom)
				(hide yes)
			)
		)
		(pin "1"
		)
		(pin "2"
		)
		(instances
			(project "artix-dc-scm"
				(path ""
					(reference "C185")
					(unit 1)
				)
			)
		)
	)
	(symbol
		(lib_id "antmicroCapacitorsmisc:C_100n_6V3_0402")
		(at 58.42 236.22 90)
		(unit 1)
		(exclude_from_sim no)
		(in_bom yes)
		(on_board yes)
		(dnp no)
		(property "Reference" "C187"
			(at 59.055 231.775 90)
			(effects
				(font
					(size 1.27 1.27)
				)
				(justify right)
			)
		)
		(property "Value" "C_100n_6V3_0402"
			(at 68.58 215.9 0)
			(effects
				(font
					(size 1.27 1.27)
					(thickness 0.15)
				)
				(justify left bottom)
				(hide yes)
			)
		)
		(property "Footprint" "antmicro-footprints:C_0402_1005Metric"
			(at 71.12 215.9 0)
			(effects
				(font
					(size 1.27 1.27)
					(thickness 0.15)
				)
				(justify left bottom)
				(hide yes)
			)
		)
		(property "Datasheet" "https://www.passivecomponent.com/wp-content/uploads/datasheet/WTC_MLCC_General_Purpose.pdf"
			(at 73.66 215.9 0)
			(effects
				(font
					(size 1.27 1.27)
					(thickness 0.15)
				)
				(justify left bottom)
				(hide yes)
			)
		)
		(property "Description" "SMT Multilayer Ceramic Capacitor, 0.1 µF, 6.3 V, 0402 [1005 Metric], ± 10%, X5R, Walsin MLCC"
			(at 58.42 236.22 0)
			(effects
				(font
					(size 1.27 1.27)
				)
				(hide yes)
			)
		)
		(property "Manufacturer" "Walsin"
			(at 78.74 215.9 0)
			(effects
				(font
					(size 1.27 1.27)
					(thickness 0.15)
				)
				(justify left bottom)
				(hide yes)
			)
		)
		(property "MPN" "0402X104K6R3CT"
			(at 76.2 215.9 0)
			(effects
				(font
					(size 1.27 1.27)
					(thickness 0.15)
				)
				(justify left bottom)
				(hide yes)
			)
		)
		(property "Val" "100n"
			(at 59.055 235.585 90)
			(effects
				(font
					(size 1.27 1.27)
					(thickness 0.15)
				)
				(justify right)
			)
		)
		(property "License" "Apache-2.0"
			(at 81.28 215.9 0)
			(effects
				(font
					(size 1.27 1.27)
					(thickness 0.15)
				)
				(justify left bottom)
				(hide yes)
			)
		)
		(property "Author" "Antmicro"
			(at 83.82 215.9 0)
			(effects
				(font
					(size 1.27 1.27)
					(thickness 0.15)
				)
				(justify left bottom)
				(hide yes)
			)
		)
		(property "Voltage" ""
			(at 86.36 215.9 0)
			(effects
				(font
					(size 1.27 1.27)
				)
				(justify left bottom)
				(hide yes)
			)
		)
		(property "Dielectric" ""
			(at 88.9 215.9 0)
			(effects
				(font
					(size 1.27 1.27)
				)
				(justify left bottom)
				(hide yes)
			)
		)
		(property "Public" "False"
			(at 91.44 215.9 0)
			(effects
				(font
					(size 1.27 1.27)
				)
				(justify left bottom)
				(hide yes)
			)
		)
		(pin "1"
		)
		(pin "2"
		)
		(instances
			(project "artix-dc-scm"
				(path ""
					(reference "C187")
					(unit 1)
				)
			)
		)
	)
	(symbol
		(lib_id "antmicroCapacitorsmisc:C_100n_6V3_0402")
		(at 50.8 236.22 90)
		(unit 1)
		(exclude_from_sim no)
		(in_bom yes)
		(on_board yes)
		(dnp no)
		(property "Reference" "C186"
			(at 51.435 231.775 90)
			(effects
				(font
					(size 1.27 1.27)
				)
				(justify right)
			)
		)
		(property "Value" "C_100n_6V3_0402"
			(at 60.96 215.9 0)
			(effects
				(font
					(size 1.27 1.27)
					(thickness 0.15)
				)
				(justify left bottom)
				(hide yes)
			)
		)
		(property "Footprint" "antmicro-footprints:C_0402_1005Metric"
			(at 63.5 215.9 0)
			(effects
				(font
					(size 1.27 1.27)
					(thickness 0.15)
				)
				(justify left bottom)
				(hide yes)
			)
		)
		(property "Datasheet" "https://www.passivecomponent.com/wp-content/uploads/datasheet/WTC_MLCC_General_Purpose.pdf"
			(at 66.04 215.9 0)
			(effects
				(font
					(size 1.27 1.27)
					(thickness 0.15)
				)
				(justify left bottom)
				(hide yes)
			)
		)
		(property "Description" "SMT Multilayer Ceramic Capacitor, 0.1 µF, 6.3 V, 0402 [1005 Metric], ± 10%, X5R, Walsin MLCC"
			(at 50.8 236.22 0)
			(effects
				(font
					(size 1.27 1.27)
				)
				(hide yes)
			)
		)
		(property "Manufacturer" "Walsin"
			(at 71.12 215.9 0)
			(effects
				(font
					(size 1.27 1.27)
					(thickness 0.15)
				)
				(justify left bottom)
				(hide yes)
			)
		)
		(property "MPN" "0402X104K6R3CT"
			(at 68.58 215.9 0)
			(effects
				(font
					(size 1.27 1.27)
					(thickness 0.15)
				)
				(justify left bottom)
				(hide yes)
			)
		)
		(property "Val" "100n"
			(at 51.435 235.585 90)
			(effects
				(font
					(size 1.27 1.27)
					(thickness 0.15)
				)
				(justify right)
			)
		)
		(property "License" "Apache-2.0"
			(at 73.66 215.9 0)
			(effects
				(font
					(size 1.27 1.27)
					(thickness 0.15)
				)
				(justify left bottom)
				(hide yes)
			)
		)
		(property "Author" "Antmicro"
			(at 76.2 215.9 0)
			(effects
				(font
					(size 1.27 1.27)
					(thickness 0.15)
				)
				(justify left bottom)
				(hide yes)
			)
		)
		(property "Voltage" ""
			(at 78.74 215.9 0)
			(effects
				(font
					(size 1.27 1.27)
				)
				(justify left bottom)
				(hide yes)
			)
		)
		(property "Dielectric" ""
			(at 81.28 215.9 0)
			(effects
				(font
					(size 1.27 1.27)
				)
				(justify left bottom)
				(hide yes)
			)
		)
		(property "Public" "False"
			(at 83.82 215.9 0)
			(effects
				(font
					(size 1.27 1.27)
				)
				(justify left bottom)
				(hide yes)
			)
		)
		(pin "1"
		)
		(pin "2"
		)
		(instances
			(project "artix-dc-scm"
				(path ""
					(reference "C186")
					(unit 1)
				)
			)
		)
	)
	(symbol
		(lib_id "antmicroCapacitorsmisc:C_100n_6V3_0402")
		(at 66.04 264.16 90)
		(unit 1)
		(exclude_from_sim no)
		(in_bom yes)
		(on_board yes)
		(dnp no)
		(property "Reference" "C189"
			(at 66.675 259.715 90)
			(effects
				(font
					(size 1.27 1.27)
				)
				(justify right)
			)
		)
		(property "Value" "C_100n_6V3_0402"
			(at 76.2 243.84 0)
			(effects
				(font
					(size 1.27 1.27)
					(thickness 0.15)
				)
				(justify left bottom)
				(hide yes)
			)
		)
		(property "Footprint" "antmicro-footprints:C_0402_1005Metric"
			(at 78.74 243.84 0)
			(effects
				(font
					(size 1.27 1.27)
					(thickness 0.15)
				)
				(justify left bottom)
				(hide yes)
			)
		)
		(property "Datasheet" "https://www.passivecomponent.com/wp-content/uploads/datasheet/WTC_MLCC_General_Purpose.pdf"
			(at 81.28 243.84 0)
			(effects
				(font
					(size 1.27 1.27)
					(thickness 0.15)
				)
				(justify left bottom)
				(hide yes)
			)
		)
		(property "Description" "SMT Multilayer Ceramic Capacitor, 0.1 µF, 6.3 V, 0402 [1005 Metric], ± 10%, X5R, Walsin MLCC"
			(at 66.04 264.16 0)
			(effects
				(font
					(size 1.27 1.27)
				)
				(hide yes)
			)
		)
		(property "Manufacturer" "Walsin"
			(at 86.36 243.84 0)
			(effects
				(font
					(size 1.27 1.27)
					(thickness 0.15)
				)
				(justify left bottom)
				(hide yes)
			)
		)
		(property "MPN" "0402X104K6R3CT"
			(at 83.82 243.84 0)
			(effects
				(font
					(size 1.27 1.27)
					(thickness 0.15)
				)
				(justify left bottom)
				(hide yes)
			)
		)
		(property "Val" "100n"
			(at 66.675 263.525 90)
			(effects
				(font
					(size 1.27 1.27)
					(thickness 0.15)
				)
				(justify right)
			)
		)
		(property "License" "Apache-2.0"
			(at 88.9 243.84 0)
			(effects
				(font
					(size 1.27 1.27)
					(thickness 0.15)
				)
				(justify left bottom)
				(hide yes)
			)
		)
		(property "Author" "Antmicro"
			(at 91.44 243.84 0)
			(effects
				(font
					(size 1.27 1.27)
					(thickness 0.15)
				)
				(justify left bottom)
				(hide yes)
			)
		)
		(property "Voltage" ""
			(at 93.98 243.84 0)
			(effects
				(font
					(size 1.27 1.27)
				)
				(justify left bottom)
				(hide yes)
			)
		)
		(property "Dielectric" ""
			(at 96.52 243.84 0)
			(effects
				(font
					(size 1.27 1.27)
				)
				(justify left bottom)
				(hide yes)
			)
		)
		(property "Public" "False"
			(at 99.06 243.84 0)
			(effects
				(font
					(size 1.27 1.27)
				)
				(justify left bottom)
				(hide yes)
			)
		)
		(pin "1"
		)
		(pin "2"
		)
		(instances
			(project "artix-dc-scm"
				(path ""
					(reference "C189")
					(unit 1)
				)
			)
		)
	)
	(symbol
		(lib_id "antmicroCapacitors0402:C_4u7_0402")
		(at 58.42 264.16 90)
		(unit 1)
		(exclude_from_sim no)
		(in_bom yes)
		(on_board yes)
		(dnp no)
		(property "Reference" "C188"
			(at 59.055 259.715 90)
			(effects
				(font
					(size 1.27 1.27)
				)
				(justify right)
			)
		)
		(property "Value" "C_4u7_0402"
			(at 68.58 243.84 0)
			(effects
				(font
					(size 1.27 1.27)
					(thickness 0.15)
				)
				(justify left bottom)
				(hide yes)
			)
		)
		(property "Footprint" "antmicro-footprints:C_0402_1005Metric"
			(at 71.12 243.84 0)
			(effects
				(font
					(size 1.27 1.27)
					(thickness 0.15)
				)
				(justify left bottom)
				(hide yes)
			)
		)
		(property "Datasheet" "https://www.murata.com/products/productdetail?partno=GRM155R61A475MEAA%23"
			(at 73.66 243.84 0)
			(effects
				(font
					(size 1.27 1.27)
					(thickness 0.15)
				)
				(justify left bottom)
				(hide yes)
			)
		)
		(property "Description" "SMD Multilayer Ceramic Capacitor, 4.7 µF, 10 V, 0402 [1005 Metric], ± 20%, X5R, GRM Series"
			(at 58.42 264.16 0)
			(effects
				(font
					(size 1.27 1.27)
				)
				(hide yes)
			)
		)
		(property "Manufacturer" "Murata"
			(at 78.74 243.84 0)
			(effects
				(font
					(size 1.27 1.27)
					(thickness 0.15)
				)
				(justify left bottom)
				(hide yes)
			)
		)
		(property "MPN" "GRM155R61A475MEAAD"
			(at 76.2 243.84 0)
			(effects
				(font
					(size 1.27 1.27)
					(thickness 0.15)
				)
				(justify left bottom)
				(hide yes)
			)
		)
		(property "Val" "4u7"
			(at 59.055 263.525 90)
			(effects
				(font
					(size 1.27 1.27)
					(thickness 0.15)
				)
				(justify right)
			)
		)
		(property "License" "Apache-2.0"
			(at 81.28 243.84 0)
			(effects
				(font
					(size 1.27 1.27)
					(thickness 0.15)
				)
				(justify left bottom)
				(hide yes)
			)
		)
		(property "Author" "Antmicro"
			(at 83.82 243.84 0)
			(effects
				(font
					(size 1.27 1.27)
					(thickness 0.15)
				)
				(justify left bottom)
				(hide yes)
			)
		)
		(property "Voltage" ""
			(at 86.36 243.84 0)
			(effects
				(font
					(size 1.27 1.27)
				)
				(justify left bottom)
				(hide yes)
			)
		)
		(property "Dielectric" ""
			(at 88.9 243.84 0)
			(effects
				(font
					(size 1.27 1.27)
				)
				(justify left bottom)
				(hide yes)
			)
		)
		(pin "1"
		)
		(pin "2"
		)
		(instances
			(project "artix-dc-scm"
				(path ""
					(reference "C188")
					(unit 1)
				)
			)
		)
	)
	(symbol
		(lib_id "antmicropower:GND")
		(at 66.04 264.16 0)
		(unit 1)
		(exclude_from_sim no)
		(in_bom yes)
		(on_board yes)
		(dnp no)
		(property "Reference" "#PWR087"
			(at 66.04 270.51 0)
			(effects
				(font
					(size 1.27 1.27)
				)
				(hide yes)
			)
		)
		(property "Value" "GND"
			(at 66.04 267.97 0)
			(effects
				(font
					(size 1.27 1.27)
				)
			)
		)
		(property "Footprint" ""
			(at 66.04 264.16 0)
			(effects
				(font
					(size 1.27 1.27)
				)
				(hide yes)
			)
		)
		(property "Datasheet" ""
			(at 66.04 264.16 0)
			(effects
				(font
					(size 1.27 1.27)
				)
				(hide yes)
			)
		)
		(property "Description" ""
			(at 66.04 264.16 0)
			(effects
				(font
					(size 1.27 1.27)
				)
				(hide yes)
			)
		)
		(property "Author" "Antmicro"
			(at 74.93 271.78 0)
			(effects
				(font
					(size 1.27 1.27)
					(thickness 0.15)
				)
				(justify left bottom)
				(hide yes)
			)
		)
		(property "License" "Apache-2.0"
			(at 74.93 274.32 0)
			(effects
				(font
					(size 1.27 1.27)
					(thickness 0.15)
				)
				(justify left bottom)
				(hide yes)
			)
		)
		(pin "1"
		)
		(instances
			(project "artix-dc-scm"
				(path ""
					(reference "#PWR087")
					(unit 1)
				)
			)
		)
	)
	(symbol
		(lib_id "antmicropower:GND")
		(at 356.87 90.17 0)
		(unit 1)
		(exclude_from_sim no)
		(in_bom yes)
		(on_board yes)
		(dnp no)
		(property "Reference" "#PWR093"
			(at 356.87 96.52 0)
			(effects
				(font
					(size 1.27 1.27)
				)
				(hide yes)
			)
		)
		(property "Value" "GND"
			(at 356.87 93.98 0)
			(effects
				(font
					(size 1.27 1.27)
				)
			)
		)
		(property "Footprint" ""
			(at 356.87 90.17 0)
			(effects
				(font
					(size 1.27 1.27)
				)
				(hide yes)
			)
		)
		(property "Datasheet" ""
			(at 356.87 90.17 0)
			(effects
				(font
					(size 1.27 1.27)
				)
				(hide yes)
			)
		)
		(property "Description" ""
			(at 356.87 90.17 0)
			(effects
				(font
					(size 1.27 1.27)
				)
				(hide yes)
			)
		)
		(property "Author" "Antmicro"
			(at 365.76 97.79 0)
			(effects
				(font
					(size 1.27 1.27)
					(thickness 0.15)
				)
				(justify left bottom)
				(hide yes)
			)
		)
		(property "License" "Apache-2.0"
			(at 365.76 100.33 0)
			(effects
				(font
					(size 1.27 1.27)
					(thickness 0.15)
				)
				(justify left bottom)
				(hide yes)
			)
		)
		(pin "1"
		)
		(instances
			(project "artix-dc-scm"
				(path ""
					(reference "#PWR093")
					(unit 1)
				)
			)
		)
	)
	(symbol
		(lib_id "antmicropower:GND")
		(at 345.44 90.17 0)
		(unit 1)
		(exclude_from_sim no)
		(in_bom yes)
		(on_board yes)
		(dnp no)
		(property "Reference" "#PWR09"
			(at 345.44 96.52 0)
			(effects
				(font
					(size 1.27 1.27)
				)
				(hide yes)
			)
		)
		(property "Value" "GND"
			(at 345.44 93.98 0)
			(effects
				(font
					(size 1.27 1.27)
				)
			)
		)
		(property "Footprint" ""
			(at 345.44 90.17 0)
			(effects
				(font
					(size 1.27 1.27)
				)
				(hide yes)
			)
		)
		(property "Datasheet" ""
			(at 345.44 90.17 0)
			(effects
				(font
					(size 1.27 1.27)
				)
				(hide yes)
			)
		)
		(property "Description" ""
			(at 345.44 90.17 0)
			(effects
				(font
					(size 1.27 1.27)
				)
				(hide yes)
			)
		)
		(property "Author" "Antmicro"
			(at 354.33 97.79 0)
			(effects
				(font
					(size 1.27 1.27)
					(thickness 0.15)
				)
				(justify left bottom)
				(hide yes)
			)
		)
		(property "License" "Apache-2.0"
			(at 354.33 100.33 0)
			(effects
				(font
					(size 1.27 1.27)
					(thickness 0.15)
				)
				(justify left bottom)
				(hide yes)
			)
		)
		(pin "1"
		)
		(instances
			(project "artix-dc-scm"
				(path ""
					(reference "#PWR09")
					(unit 1)
				)
			)
		)
	)
	(symbol
		(lib_id "antmicropower:GND")
		(at 58.42 236.22 0)
		(unit 1)
		(exclude_from_sim no)
		(in_bom yes)
		(on_board yes)
		(dnp no)
		(property "Reference" "#PWR049"
			(at 58.42 242.57 0)
			(effects
				(font
					(size 1.27 1.27)
				)
				(hide yes)
			)
		)
		(property "Value" "GND"
			(at 58.42 240.03 0)
			(effects
				(font
					(size 1.27 1.27)
				)
			)
		)
		(property "Footprint" ""
			(at 58.42 236.22 0)
			(effects
				(font
					(size 1.27 1.27)
				)
				(hide yes)
			)
		)
		(property "Datasheet" ""
			(at 58.42 236.22 0)
			(effects
				(font
					(size 1.27 1.27)
				)
				(hide yes)
			)
		)
		(property "Description" ""
			(at 58.42 236.22 0)
			(effects
				(font
					(size 1.27 1.27)
				)
				(hide yes)
			)
		)
		(property "Author" "Antmicro"
			(at 67.31 243.84 0)
			(effects
				(font
					(size 1.27 1.27)
					(thickness 0.15)
				)
				(justify left bottom)
				(hide yes)
			)
		)
		(property "License" "Apache-2.0"
			(at 67.31 246.38 0)
			(effects
				(font
					(size 1.27 1.27)
					(thickness 0.15)
				)
				(justify left bottom)
				(hide yes)
			)
		)
		(pin "1"
		)
		(instances
			(project "artix-dc-scm"
				(path ""
					(reference "#PWR049")
					(unit 1)
				)
			)
		)
	)
	(symbol
		(lib_id "antmicroResistors0402:R_1k_0402")
		(at 347.98 63.5 0)
		(unit 1)
		(exclude_from_sim no)
		(in_bom yes)
		(on_board yes)
		(dnp no)
		(property "Reference" "R6"
			(at 353.06 62.23 0)
			(effects
				(font
					(size 1.27 1.27)
				)
				(justify left)
			)
		)
		(property "Value" "R_1k_0402"
			(at 368.3 76.2 0)
			(effects
				(font
					(size 1.27 1.27)
					(thickness 0.15)
				)
				(justify left bottom)
				(hide yes)
			)
		)
		(property "Footprint" "antmicro-footprints:R_0402_1005Metric"
			(at 368.3 78.74 0)
			(effects
				(font
					(size 1.27 1.27)
					(thickness 0.15)
				)
				(justify left bottom)
				(hide yes)
			)
		)
		(property "Datasheet" "https://www.bourns.com/docs/product-datasheets/cr.pdf"
			(at 368.3 81.28 0)
			(effects
				(font
					(size 1.27 1.27)
					(thickness 0.15)
				)
				(justify left bottom)
				(hide yes)
			)
		)
		(property "Description" "SMD Chip Resistor, 1 kohm, ± 1%, 63 mW, 0402 [1005 Metric], Thick Film, General Purpose"
			(at 347.98 63.5 0)
			(effects
				(font
					(size 1.27 1.27)
				)
				(hide yes)
			)
		)
		(property "Manufacturer" "Bourns"
			(at 368.3 86.36 0)
			(effects
				(font
					(size 1.27 1.27)
					(thickness 0.15)
				)
				(justify left bottom)
				(hide yes)
			)
		)
		(property "MPN" "CR0402-FX-1001GLF"
			(at 368.3 83.82 0)
			(effects
				(font
					(size 1.27 1.27)
					(thickness 0.15)
				)
				(justify left bottom)
				(hide yes)
			)
		)
		(property "Val" "1k"
			(at 346.71 62.23 0)
			(effects
				(font
					(size 1.27 1.27)
					(thickness 0.15)
				)
			)
		)
		(property "License" "Apache-2.0"
			(at 368.3 88.9 0)
			(effects
				(font
					(size 1.27 1.27)
					(thickness 0.15)
				)
				(justify left bottom)
				(hide yes)
			)
		)
		(property "Author" "Antmicro"
			(at 368.3 91.44 0)
			(effects
				(font
					(size 1.27 1.27)
					(thickness 0.15)
				)
				(justify left bottom)
				(hide yes)
			)
		)
		(property "Tolerance" "1%"
			(at 368.3 73.66 0)
			(effects
				(font
					(size 1.27 1.27)
				)
				(justify left bottom)
				(hide yes)
			)
		)
		(pin "1"
		)
		(pin "2"
		)
		(instances
			(project "artix-dc-scm"
				(path ""
					(reference "R6")
					(unit 1)
				)
			)
		)
	)
	(symbol
		(lib_id "antmicroUSBConnectors:USB-Micro-B_Amphenol_10118192-0001LF")
		(at 133.35 74.93 0)
		(unit 1)
		(exclude_from_sim no)
		(in_bom yes)
		(on_board yes)
		(dnp no)
		(fields_autoplaced yes)
		(property "Reference" "J3"
			(at 109.855 85.09 0)
			(effects
				(font
					(size 1.27 1.27)
				)
				(justify right)
			)
		)
		(property "Value" "USB-Micro-B_Amphenol_10118192-0001LF"
			(at 157.48 77.47 0)
			(effects
				(font
					(size 1.27 1.27)
					(thickness 0.15)
				)
				(justify left bottom)
				(hide yes)
			)
		)
		(property "Footprint" "antmicro-footprints:USB-Micro-B_Receptacle_Amphenol_10118192"
			(at 166.37 82.55 0)
			(effects
				(font
					(size 1.27 1.27)
					(thickness 0.15)
				)
				(justify left bottom)
				(hide yes)
			)
		)
		(property "Datasheet" "http://www.amphenol-icc.com/media/wysiwyg/files/drawing/10118192.pdf"
			(at 166.37 85.09 0)
			(effects
				(font
					(size 1.27 1.27)
					(thickness 0.15)
				)
				(justify left bottom)
				(hide yes)
			)
		)
		(property "Description" "USB - micro B USB 2.0 Receptacle Connector 5 Position Surface Mount, Right Angle"
			(at 133.35 74.93 0)
			(effects
				(font
					(size 1.27 1.27)
				)
				(hide yes)
			)
		)
		(property "MPN" "10118192-0001LF"
			(at 166.37 87.63 0)
			(effects
				(font
					(size 1.27 1.27)
					(thickness 0.15)
				)
				(justify left bottom)
				(hide yes)
			)
		)
		(property "Manufacturer" "Amphenol"
			(at 166.37 90.17 0)
			(effects
				(font
					(size 1.27 1.27)
					(thickness 0.15)
				)
				(justify left bottom)
				(hide yes)
			)
		)
		(property "Author" "Antmicro"
			(at 166.37 95.25 0)
			(effects
				(font
					(size 1.27 1.27)
					(thickness 0.15)
				)
				(justify left bottom)
				(hide yes)
			)
		)
		(property "License" "Apache-2.0"
			(at 166.37 97.79 0)
			(effects
				(font
					(size 1.27 1.27)
					(thickness 0.15)
				)
				(justify left bottom)
				(hide yes)
			)
		)
		(property "VSD_class" "USB Micro"
			(at 166.37 92.71 0)
			(effects
				(font
					(size 1.27 1.27)
					(thickness 0.15)
				)
				(justify left bottom)
				(hide yes)
			)
		)
		(pin "1"
		)
		(pin "2"
		)
		(pin "3"
		)
		(pin "4"
		)
		(pin "5"
		)
		(pin "SH"
		)
		(instances
			(project "artix-dc-scm"
				(path ""
					(reference "J3")
					(unit 1)
				)
			)
		)
	)
	(symbol
		(lib_id "antmicroCapacitors0402:C_100n_0402")
		(at 393.7 30.48 90)
		(unit 1)
		(exclude_from_sim no)
		(in_bom yes)
		(on_board yes)
		(dnp no)
		(property "Reference" "C20"
			(at 394.335 26.035 90)
			(effects
				(font
					(size 1.27 1.27)
				)
				(justify right)
			)
		)
		(property "Value" "C_100n_0402"
			(at 403.86 10.16 0)
			(effects
				(font
					(size 1.27 1.27)
					(thickness 0.15)
				)
				(justify left bottom)
				(hide yes)
			)
		)
		(property "Footprint" "antmicro-footprints:C_0402_1005Metric"
			(at 406.4 10.16 0)
			(effects
				(font
					(size 1.27 1.27)
					(thickness 0.15)
				)
				(justify left bottom)
				(hide yes)
			)
		)
		(property "Datasheet" "https://www.murata.com/products/productdetail?partno=GRM155R61H104KE14%23"
			(at 408.94 10.16 0)
			(effects
				(font
					(size 1.27 1.27)
					(thickness 0.15)
				)
				(justify left bottom)
				(hide yes)
			)
		)
		(property "Description" "SMD Multilayer Ceramic Capacitor, 0.1 µF, 50 V, 0402 [1005 Metric], ± 10%, X5R, GRM Series"
			(at 393.7 30.48 0)
			(effects
				(font
					(size 1.27 1.27)
				)
				(hide yes)
			)
		)
		(property "Manufacturer" "Murata"
			(at 414.02 10.16 0)
			(effects
				(font
					(size 1.27 1.27)
					(thickness 0.15)
				)
				(justify left bottom)
				(hide yes)
			)
		)
		(property "MPN" "GRM155R61H104KE14D"
			(at 411.48 10.16 0)
			(effects
				(font
					(size 1.27 1.27)
					(thickness 0.15)
				)
				(justify left bottom)
				(hide yes)
			)
		)
		(property "Val" "100n"
			(at 394.335 29.845 90)
			(effects
				(font
					(size 1.27 1.27)
					(thickness 0.15)
				)
				(justify right)
			)
		)
		(property "License" "Apache-2.0"
			(at 416.56 10.16 0)
			(effects
				(font
					(size 1.27 1.27)
					(thickness 0.15)
				)
				(justify left bottom)
				(hide yes)
			)
		)
		(property "Author" "Antmicro"
			(at 419.1 10.16 0)
			(effects
				(font
					(size 1.27 1.27)
					(thickness 0.15)
				)
				(justify left bottom)
				(hide yes)
			)
		)
		(property "Voltage" "50V"
			(at 421.64 10.16 0)
			(effects
				(font
					(size 1.27 1.27)
				)
				(justify left bottom)
				(hide yes)
			)
		)
		(property "Dielectric" "X5R"
			(at 424.18 10.16 0)
			(effects
				(font
					(size 1.27 1.27)
				)
				(justify left bottom)
				(hide yes)
			)
		)
		(pin "1"
		)
		(pin "2"
		)
		(instances
			(project "artix-dc-scm"
				(path ""
					(reference "C20")
					(unit 1)
				)
			)
		)
	)
	(symbol
		(lib_id "antmicroResistors0402:R_47k_0402")
		(at 140.97 237.49 270)
		(unit 1)
		(exclude_from_sim no)
		(in_bom yes)
		(on_board yes)
		(dnp no)
		(property "Reference" "R126"
			(at 139.7 232.41 0)
			(effects
				(font
					(size 1.27 1.27)
				)
				(justify left)
			)
		)
		(property "Value" "R_47k_0402"
			(at 128.27 257.81 0)
			(effects
				(font
					(size 1.27 1.27)
					(thickness 0.15)
				)
				(justify left bottom)
				(hide yes)
			)
		)
		(property "Footprint" "antmicro-footprints:R_0402_1005Metric"
			(at 125.73 257.81 0)
			(effects
				(font
					(size 1.27 1.27)
					(thickness 0.15)
				)
				(justify left bottom)
				(hide yes)
			)
		)
		(property "Datasheet" "https://www.bourns.com/docs/product-datasheets/cr.pdf"
			(at 123.19 257.81 0)
			(effects
				(font
					(size 1.27 1.27)
					(thickness 0.15)
				)
				(justify left bottom)
				(hide yes)
			)
		)
		(property "Description" "SMD Chip Resistor, 47 kohm, ± 1%, 62.5 mW, 0402 [1005 Metric], Thick Film, General Purpose"
			(at 140.97 237.49 0)
			(effects
				(font
					(size 1.27 1.27)
				)
				(hide yes)
			)
		)
		(property "Manufacturer" "Bourns"
			(at 118.11 257.81 0)
			(effects
				(font
					(size 1.27 1.27)
					(thickness 0.15)
				)
				(justify left bottom)
				(hide yes)
			)
		)
		(property "MPN" "CR0402-FX-4702GLF"
			(at 120.65 257.81 0)
			(effects
				(font
					(size 1.27 1.27)
					(thickness 0.15)
				)
				(justify left bottom)
				(hide yes)
			)
		)
		(property "Val" "47k"
			(at 139.7 242.57 0)
			(effects
				(font
					(size 1.27 1.27)
					(thickness 0.15)
				)
				(justify left)
			)
		)
		(property "License" "Apache-2.0"
			(at 115.57 257.81 0)
			(effects
				(font
					(size 1.27 1.27)
					(thickness 0.15)
				)
				(justify left bottom)
				(hide yes)
			)
		)
		(property "Author" "Antmicro"
			(at 113.03 257.81 0)
			(effects
				(font
					(size 1.27 1.27)
					(thickness 0.15)
				)
				(justify left bottom)
				(hide yes)
			)
		)
		(property "Tolerance" "1%"
			(at 130.81 257.81 0)
			(effects
				(font
					(size 1.27 1.27)
				)
				(justify left bottom)
				(hide yes)
			)
		)
		(pin "1"
		)
		(pin "2"
		)
		(instances
			(project "artix-dc-scm"
				(path ""
					(reference "R126")
					(unit 1)
				)
			)
		)
	)
	(symbol
		(lib_id "antmicroResistors0402:R_47k_0402")
		(at 106.68 237.49 270)
		(unit 1)
		(exclude_from_sim no)
		(in_bom yes)
		(on_board yes)
		(dnp no)
		(property "Reference" "R117"
			(at 105.41 232.41 0)
			(effects
				(font
					(size 1.27 1.27)
				)
				(justify left)
			)
		)
		(property "Value" "R_47k_0402"
			(at 93.98 257.81 0)
			(effects
				(font
					(size 1.27 1.27)
					(thickness 0.15)
				)
				(justify left bottom)
				(hide yes)
			)
		)
		(property "Footprint" "antmicro-footprints:R_0402_1005Metric"
			(at 91.44 257.81 0)
			(effects
				(font
					(size 1.27 1.27)
					(thickness 0.15)
				)
				(justify left bottom)
				(hide yes)
			)
		)
		(property "Datasheet" "https://www.bourns.com/docs/product-datasheets/cr.pdf"
			(at 88.9 257.81 0)
			(effects
				(font
					(size 1.27 1.27)
					(thickness 0.15)
				)
				(justify left bottom)
				(hide yes)
			)
		)
		(property "Description" "SMD Chip Resistor, 47 kohm, ± 1%, 62.5 mW, 0402 [1005 Metric], Thick Film, General Purpose"
			(at 106.68 237.49 0)
			(effects
				(font
					(size 1.27 1.27)
				)
				(hide yes)
			)
		)
		(property "Manufacturer" "Bourns"
			(at 83.82 257.81 0)
			(effects
				(font
					(size 1.27 1.27)
					(thickness 0.15)
				)
				(justify left bottom)
				(hide yes)
			)
		)
		(property "MPN" "CR0402-FX-4702GLF"
			(at 86.36 257.81 0)
			(effects
				(font
					(size 1.27 1.27)
					(thickness 0.15)
				)
				(justify left bottom)
				(hide yes)
			)
		)
		(property "Val" "47k"
			(at 105.41 242.57 0)
			(effects
				(font
					(size 1.27 1.27)
					(thickness 0.15)
				)
				(justify left)
			)
		)
		(property "License" "Apache-2.0"
			(at 81.28 257.81 0)
			(effects
				(font
					(size 1.27 1.27)
					(thickness 0.15)
				)
				(justify left bottom)
				(hide yes)
			)
		)
		(property "Author" "Antmicro"
			(at 78.74 257.81 0)
			(effects
				(font
					(size 1.27 1.27)
					(thickness 0.15)
				)
				(justify left bottom)
				(hide yes)
			)
		)
		(property "Tolerance" "1%"
			(at 96.52 257.81 0)
			(effects
				(font
					(size 1.27 1.27)
				)
				(justify left bottom)
				(hide yes)
			)
		)
		(pin "1"
		)
		(pin "2"
		)
		(instances
			(project "artix-dc-scm"
				(path ""
					(reference "R117")
					(unit 1)
				)
			)
		)
	)
	(symbol
		(lib_id "antmicroResistors0402:R_47k_0402")
		(at 110.49 237.49 270)
		(unit 1)
		(exclude_from_sim no)
		(in_bom yes)
		(on_board yes)
		(dnp no)
		(property "Reference" "R118"
			(at 109.22 232.41 0)
			(effects
				(font
					(size 1.27 1.27)
				)
				(justify left)
			)
		)
		(property "Value" "R_47k_0402"
			(at 97.79 257.81 0)
			(effects
				(font
					(size 1.27 1.27)
					(thickness 0.15)
				)
				(justify left bottom)
				(hide yes)
			)
		)
		(property "Footprint" "antmicro-footprints:R_0402_1005Metric"
			(at 95.25 257.81 0)
			(effects
				(font
					(size 1.27 1.27)
					(thickness 0.15)
				)
				(justify left bottom)
				(hide yes)
			)
		)
		(property "Datasheet" "https://www.bourns.com/docs/product-datasheets/cr.pdf"
			(at 92.71 257.81 0)
			(effects
				(font
					(size 1.27 1.27)
					(thickness 0.15)
				)
				(justify left bottom)
				(hide yes)
			)
		)
		(property "Description" "SMD Chip Resistor, 47 kohm, ± 1%, 62.5 mW, 0402 [1005 Metric], Thick Film, General Purpose"
			(at 110.49 237.49 0)
			(effects
				(font
					(size 1.27 1.27)
				)
				(hide yes)
			)
		)
		(property "Manufacturer" "Bourns"
			(at 87.63 257.81 0)
			(effects
				(font
					(size 1.27 1.27)
					(thickness 0.15)
				)
				(justify left bottom)
				(hide yes)
			)
		)
		(property "MPN" "CR0402-FX-4702GLF"
			(at 90.17 257.81 0)
			(effects
				(font
					(size 1.27 1.27)
					(thickness 0.15)
				)
				(justify left bottom)
				(hide yes)
			)
		)
		(property "Val" "47k"
			(at 109.22 242.57 0)
			(effects
				(font
					(size 1.27 1.27)
					(thickness 0.15)
				)
				(justify left)
			)
		)
		(property "License" "Apache-2.0"
			(at 85.09 257.81 0)
			(effects
				(font
					(size 1.27 1.27)
					(thickness 0.15)
				)
				(justify left bottom)
				(hide yes)
			)
		)
		(property "Author" "Antmicro"
			(at 82.55 257.81 0)
			(effects
				(font
					(size 1.27 1.27)
					(thickness 0.15)
				)
				(justify left bottom)
				(hide yes)
			)
		)
		(property "Tolerance" "1%"
			(at 100.33 257.81 0)
			(effects
				(font
					(size 1.27 1.27)
				)
				(justify left bottom)
				(hide yes)
			)
		)
		(pin "1"
		)
		(pin "2"
		)
		(instances
			(project "artix-dc-scm"
				(path ""
					(reference "R118")
					(unit 1)
				)
			)
		)
	)
	(symbol
		(lib_id "antmicroResistors0402:R_47k_0402")
		(at 114.3 237.49 270)
		(unit 1)
		(exclude_from_sim no)
		(in_bom yes)
		(on_board yes)
		(dnp no)
		(property "Reference" "R119"
			(at 113.03 232.41 0)
			(effects
				(font
					(size 1.27 1.27)
				)
				(justify left)
			)
		)
		(property "Value" "R_47k_0402"
			(at 101.6 257.81 0)
			(effects
				(font
					(size 1.27 1.27)
					(thickness 0.15)
				)
				(justify left bottom)
				(hide yes)
			)
		)
		(property "Footprint" "antmicro-footprints:R_0402_1005Metric"
			(at 99.06 257.81 0)
			(effects
				(font
					(size 1.27 1.27)
					(thickness 0.15)
				)
				(justify left bottom)
				(hide yes)
			)
		)
		(property "Datasheet" "https://www.bourns.com/docs/product-datasheets/cr.pdf"
			(at 96.52 257.81 0)
			(effects
				(font
					(size 1.27 1.27)
					(thickness 0.15)
				)
				(justify left bottom)
				(hide yes)
			)
		)
		(property "Description" "SMD Chip Resistor, 47 kohm, ± 1%, 62.5 mW, 0402 [1005 Metric], Thick Film, General Purpose"
			(at 114.3 237.49 0)
			(effects
				(font
					(size 1.27 1.27)
				)
				(hide yes)
			)
		)
		(property "Manufacturer" "Bourns"
			(at 91.44 257.81 0)
			(effects
				(font
					(size 1.27 1.27)
					(thickness 0.15)
				)
				(justify left bottom)
				(hide yes)
			)
		)
		(property "MPN" "CR0402-FX-4702GLF"
			(at 93.98 257.81 0)
			(effects
				(font
					(size 1.27 1.27)
					(thickness 0.15)
				)
				(justify left bottom)
				(hide yes)
			)
		)
		(property "Val" "47k"
			(at 113.03 242.57 0)
			(effects
				(font
					(size 1.27 1.27)
					(thickness 0.15)
				)
				(justify left)
			)
		)
		(property "License" "Apache-2.0"
			(at 88.9 257.81 0)
			(effects
				(font
					(size 1.27 1.27)
					(thickness 0.15)
				)
				(justify left bottom)
				(hide yes)
			)
		)
		(property "Author" "Antmicro"
			(at 86.36 257.81 0)
			(effects
				(font
					(size 1.27 1.27)
					(thickness 0.15)
				)
				(justify left bottom)
				(hide yes)
			)
		)
		(property "Tolerance" "1%"
			(at 104.14 257.81 0)
			(effects
				(font
					(size 1.27 1.27)
				)
				(justify left bottom)
				(hide yes)
			)
		)
		(pin "1"
		)
		(pin "2"
		)
		(instances
			(project "artix-dc-scm"
				(path ""
					(reference "R119")
					(unit 1)
				)
			)
		)
	)
	(symbol
		(lib_id "antmicroCapacitors0402:C_4u7_0402")
		(at 400.05 134.62 90)
		(unit 1)
		(exclude_from_sim no)
		(in_bom yes)
		(on_board yes)
		(dnp no)
		(property "Reference" "C245"
			(at 400.685 130.175 90)
			(effects
				(font
					(size 1.27 1.27)
				)
				(justify right)
			)
		)
		(property "Value" "C_4u7_0402"
			(at 410.21 114.3 0)
			(effects
				(font
					(size 1.27 1.27)
					(thickness 0.15)
				)
				(justify left bottom)
				(hide yes)
			)
		)
		(property "Footprint" "antmicro-footprints:C_0402_1005Metric"
			(at 412.75 114.3 0)
			(effects
				(font
					(size 1.27 1.27)
					(thickness 0.15)
				)
				(justify left bottom)
				(hide yes)
			)
		)
		(property "Datasheet" "https://www.murata.com/products/productdetail?partno=GRM155R61A475MEAA%23"
			(at 415.29 114.3 0)
			(effects
				(font
					(size 1.27 1.27)
					(thickness 0.15)
				)
				(justify left bottom)
				(hide yes)
			)
		)
		(property "Description" "SMD Multilayer Ceramic Capacitor, 4.7 µF, 10 V, 0402 [1005 Metric], ± 20%, X5R, GRM Series"
			(at 400.05 134.62 0)
			(effects
				(font
					(size 1.27 1.27)
				)
				(hide yes)
			)
		)
		(property "Manufacturer" "Murata"
			(at 420.37 114.3 0)
			(effects
				(font
					(size 1.27 1.27)
					(thickness 0.15)
				)
				(justify left bottom)
				(hide yes)
			)
		)
		(property "MPN" "GRM155R61A475MEAAD"
			(at 417.83 114.3 0)
			(effects
				(font
					(size 1.27 1.27)
					(thickness 0.15)
				)
				(justify left bottom)
				(hide yes)
			)
		)
		(property "Val" "4u7"
			(at 400.685 133.985 90)
			(effects
				(font
					(size 1.27 1.27)
					(thickness 0.15)
				)
				(justify right)
			)
		)
		(property "License" "Apache-2.0"
			(at 422.91 114.3 0)
			(effects
				(font
					(size 1.27 1.27)
					(thickness 0.15)
				)
				(justify left bottom)
				(hide yes)
			)
		)
		(property "Author" "Antmicro"
			(at 425.45 114.3 0)
			(effects
				(font
					(size 1.27 1.27)
					(thickness 0.15)
				)
				(justify left bottom)
				(hide yes)
			)
		)
		(property "Voltage" ""
			(at 427.99 114.3 0)
			(effects
				(font
					(size 1.27 1.27)
				)
				(justify left bottom)
				(hide yes)
			)
		)
		(property "Dielectric" ""
			(at 430.53 114.3 0)
			(effects
				(font
					(size 1.27 1.27)
				)
				(justify left bottom)
				(hide yes)
			)
		)
		(pin "1"
		)
		(pin "2"
		)
		(instances
			(project "artix-dc-scm"
				(path ""
					(reference "C245")
					(unit 1)
				)
			)
		)
	)
	(symbol
		(lib_id "antmicroCapacitors0402:C_4u7_0402")
		(at 400.05 123.19 90)
		(unit 1)
		(exclude_from_sim no)
		(in_bom yes)
		(on_board yes)
		(dnp no)
		(property "Reference" "C177"
			(at 400.685 118.745 90)
			(effects
				(font
					(size 1.27 1.27)
				)
				(justify right)
			)
		)
		(property "Value" "C_4u7_0402"
			(at 410.21 102.87 0)
			(effects
				(font
					(size 1.27 1.27)
					(thickness 0.15)
				)
				(justify left bottom)
				(hide yes)
			)
		)
		(property "Footprint" "antmicro-footprints:C_0402_1005Metric"
			(at 412.75 102.87 0)
			(effects
				(font
					(size 1.27 1.27)
					(thickness 0.15)
				)
				(justify left bottom)
				(hide yes)
			)
		)
		(property "Datasheet" "https://www.murata.com/products/productdetail?partno=GRM155R61A475MEAA%23"
			(at 415.29 102.87 0)
			(effects
				(font
					(size 1.27 1.27)
					(thickness 0.15)
				)
				(justify left bottom)
				(hide yes)
			)
		)
		(property "Description" "SMD Multilayer Ceramic Capacitor, 4.7 µF, 10 V, 0402 [1005 Metric], ± 20%, X5R, GRM Series"
			(at 400.05 123.19 0)
			(effects
				(font
					(size 1.27 1.27)
				)
				(hide yes)
			)
		)
		(property "Manufacturer" "Murata"
			(at 420.37 102.87 0)
			(effects
				(font
					(size 1.27 1.27)
					(thickness 0.15)
				)
				(justify left bottom)
				(hide yes)
			)
		)
		(property "MPN" "GRM155R61A475MEAAD"
			(at 417.83 102.87 0)
			(effects
				(font
					(size 1.27 1.27)
					(thickness 0.15)
				)
				(justify left bottom)
				(hide yes)
			)
		)
		(property "Val" "4u7"
			(at 400.685 122.555 90)
			(effects
				(font
					(size 1.27 1.27)
					(thickness 0.15)
				)
				(justify right)
			)
		)
		(property "License" "Apache-2.0"
			(at 422.91 102.87 0)
			(effects
				(font
					(size 1.27 1.27)
					(thickness 0.15)
				)
				(justify left bottom)
				(hide yes)
			)
		)
		(property "Author" "Antmicro"
			(at 425.45 102.87 0)
			(effects
				(font
					(size 1.27 1.27)
					(thickness 0.15)
				)
				(justify left bottom)
				(hide yes)
			)
		)
		(property "Voltage" ""
			(at 427.99 102.87 0)
			(effects
				(font
					(size 1.27 1.27)
				)
				(justify left bottom)
				(hide yes)
			)
		)
		(property "Dielectric" ""
			(at 430.53 102.87 0)
			(effects
				(font
					(size 1.27 1.27)
				)
				(justify left bottom)
				(hide yes)
			)
		)
		(pin "1"
		)
		(pin "2"
		)
		(instances
			(project "artix-dc-scm"
				(path ""
					(reference "C177")
					(unit 1)
				)
			)
		)
	)
	(symbol
		(lib_id "antmicroResistors0402:R_47k_0402")
		(at 118.11 237.49 270)
		(unit 1)
		(exclude_from_sim no)
		(in_bom yes)
		(on_board yes)
		(dnp no)
		(property "Reference" "R120"
			(at 116.84 232.41 0)
			(effects
				(font
					(size 1.27 1.27)
				)
				(justify left)
			)
		)
		(property "Value" "R_47k_0402"
			(at 105.41 257.81 0)
			(effects
				(font
					(size 1.27 1.27)
					(thickness 0.15)
				)
				(justify left bottom)
				(hide yes)
			)
		)
		(property "Footprint" "antmicro-footprints:R_0402_1005Metric"
			(at 102.87 257.81 0)
			(effects
				(font
					(size 1.27 1.27)
					(thickness 0.15)
				)
				(justify left bottom)
				(hide yes)
			)
		)
		(property "Datasheet" "https://www.bourns.com/docs/product-datasheets/cr.pdf"
			(at 100.33 257.81 0)
			(effects
				(font
					(size 1.27 1.27)
					(thickness 0.15)
				)
				(justify left bottom)
				(hide yes)
			)
		)
		(property "Description" "SMD Chip Resistor, 47 kohm, ± 1%, 62.5 mW, 0402 [1005 Metric], Thick Film, General Purpose"
			(at 118.11 237.49 0)
			(effects
				(font
					(size 1.27 1.27)
				)
				(hide yes)
			)
		)
		(property "Manufacturer" "Bourns"
			(at 95.25 257.81 0)
			(effects
				(font
					(size 1.27 1.27)
					(thickness 0.15)
				)
				(justify left bottom)
				(hide yes)
			)
		)
		(property "MPN" "CR0402-FX-4702GLF"
			(at 97.79 257.81 0)
			(effects
				(font
					(size 1.27 1.27)
					(thickness 0.15)
				)
				(justify left bottom)
				(hide yes)
			)
		)
		(property "Val" "47k"
			(at 116.84 242.57 0)
			(effects
				(font
					(size 1.27 1.27)
					(thickness 0.15)
				)
				(justify left)
			)
		)
		(property "License" "Apache-2.0"
			(at 92.71 257.81 0)
			(effects
				(font
					(size 1.27 1.27)
					(thickness 0.15)
				)
				(justify left bottom)
				(hide yes)
			)
		)
		(property "Author" "Antmicro"
			(at 90.17 257.81 0)
			(effects
				(font
					(size 1.27 1.27)
					(thickness 0.15)
				)
				(justify left bottom)
				(hide yes)
			)
		)
		(property "Tolerance" "1%"
			(at 107.95 257.81 0)
			(effects
				(font
					(size 1.27 1.27)
				)
				(justify left bottom)
				(hide yes)
			)
		)
		(pin "1"
		)
		(pin "2"
		)
		(instances
			(project "artix-dc-scm"
				(path ""
					(reference "R120")
					(unit 1)
				)
			)
		)
	)
	(symbol
		(lib_id "antmicroResistors0402:R_47k_0402")
		(at 121.92 237.49 270)
		(unit 1)
		(exclude_from_sim no)
		(in_bom yes)
		(on_board yes)
		(dnp no)
		(property "Reference" "R121"
			(at 120.65 232.41 0)
			(effects
				(font
					(size 1.27 1.27)
				)
				(justify left)
			)
		)
		(property "Value" "R_47k_0402"
			(at 109.22 257.81 0)
			(effects
				(font
					(size 1.27 1.27)
					(thickness 0.15)
				)
				(justify left bottom)
				(hide yes)
			)
		)
		(property "Footprint" "antmicro-footprints:R_0402_1005Metric"
			(at 106.68 257.81 0)
			(effects
				(font
					(size 1.27 1.27)
					(thickness 0.15)
				)
				(justify left bottom)
				(hide yes)
			)
		)
		(property "Datasheet" "https://www.bourns.com/docs/product-datasheets/cr.pdf"
			(at 104.14 257.81 0)
			(effects
				(font
					(size 1.27 1.27)
					(thickness 0.15)
				)
				(justify left bottom)
				(hide yes)
			)
		)
		(property "Description" "SMD Chip Resistor, 47 kohm, ± 1%, 62.5 mW, 0402 [1005 Metric], Thick Film, General Purpose"
			(at 121.92 237.49 0)
			(effects
				(font
					(size 1.27 1.27)
				)
				(hide yes)
			)
		)
		(property "Manufacturer" "Bourns"
			(at 99.06 257.81 0)
			(effects
				(font
					(size 1.27 1.27)
					(thickness 0.15)
				)
				(justify left bottom)
				(hide yes)
			)
		)
		(property "MPN" "CR0402-FX-4702GLF"
			(at 101.6 257.81 0)
			(effects
				(font
					(size 1.27 1.27)
					(thickness 0.15)
				)
				(justify left bottom)
				(hide yes)
			)
		)
		(property "Val" "47k"
			(at 120.65 242.57 0)
			(effects
				(font
					(size 1.27 1.27)
					(thickness 0.15)
				)
				(justify left)
			)
		)
		(property "License" "Apache-2.0"
			(at 96.52 257.81 0)
			(effects
				(font
					(size 1.27 1.27)
					(thickness 0.15)
				)
				(justify left bottom)
				(hide yes)
			)
		)
		(property "Author" "Antmicro"
			(at 93.98 257.81 0)
			(effects
				(font
					(size 1.27 1.27)
					(thickness 0.15)
				)
				(justify left bottom)
				(hide yes)
			)
		)
		(property "Tolerance" "1%"
			(at 111.76 257.81 0)
			(effects
				(font
					(size 1.27 1.27)
				)
				(justify left bottom)
				(hide yes)
			)
		)
		(pin "1"
		)
		(pin "2"
		)
		(instances
			(project "artix-dc-scm"
				(path ""
					(reference "R121")
					(unit 1)
				)
			)
		)
	)
	(symbol
		(lib_id "antmicroResistors0402:R_47k_0402")
		(at 125.73 237.49 270)
		(unit 1)
		(exclude_from_sim no)
		(in_bom yes)
		(on_board yes)
		(dnp no)
		(property "Reference" "R122"
			(at 124.46 232.41 0)
			(effects
				(font
					(size 1.27 1.27)
				)
				(justify left)
			)
		)
		(property "Value" "R_47k_0402"
			(at 113.03 257.81 0)
			(effects
				(font
					(size 1.27 1.27)
					(thickness 0.15)
				)
				(justify left bottom)
				(hide yes)
			)
		)
		(property "Footprint" "antmicro-footprints:R_0402_1005Metric"
			(at 110.49 257.81 0)
			(effects
				(font
					(size 1.27 1.27)
					(thickness 0.15)
				)
				(justify left bottom)
				(hide yes)
			)
		)
		(property "Datasheet" "https://www.bourns.com/docs/product-datasheets/cr.pdf"
			(at 107.95 257.81 0)
			(effects
				(font
					(size 1.27 1.27)
					(thickness 0.15)
				)
				(justify left bottom)
				(hide yes)
			)
		)
		(property "Description" "SMD Chip Resistor, 47 kohm, ± 1%, 62.5 mW, 0402 [1005 Metric], Thick Film, General Purpose"
			(at 125.73 237.49 0)
			(effects
				(font
					(size 1.27 1.27)
				)
				(hide yes)
			)
		)
		(property "Manufacturer" "Bourns"
			(at 102.87 257.81 0)
			(effects
				(font
					(size 1.27 1.27)
					(thickness 0.15)
				)
				(justify left bottom)
				(hide yes)
			)
		)
		(property "MPN" "CR0402-FX-4702GLF"
			(at 105.41 257.81 0)
			(effects
				(font
					(size 1.27 1.27)
					(thickness 0.15)
				)
				(justify left bottom)
				(hide yes)
			)
		)
		(property "Val" "47k"
			(at 124.46 242.57 0)
			(effects
				(font
					(size 1.27 1.27)
					(thickness 0.15)
				)
				(justify left)
			)
		)
		(property "License" "Apache-2.0"
			(at 100.33 257.81 0)
			(effects
				(font
					(size 1.27 1.27)
					(thickness 0.15)
				)
				(justify left bottom)
				(hide yes)
			)
		)
		(property "Author" "Antmicro"
			(at 97.79 257.81 0)
			(effects
				(font
					(size 1.27 1.27)
					(thickness 0.15)
				)
				(justify left bottom)
				(hide yes)
			)
		)
		(property "Tolerance" "1%"
			(at 115.57 257.81 0)
			(effects
				(font
					(size 1.27 1.27)
				)
				(justify left bottom)
				(hide yes)
			)
		)
		(pin "1"
		)
		(pin "2"
		)
		(instances
			(project "artix-dc-scm"
				(path ""
					(reference "R122")
					(unit 1)
				)
			)
		)
	)
	(symbol
		(lib_id "antmicroResistors0402:R_47k_0402")
		(at 129.54 237.49 270)
		(unit 1)
		(exclude_from_sim no)
		(in_bom yes)
		(on_board yes)
		(dnp no)
		(property "Reference" "R123"
			(at 128.27 232.41 0)
			(effects
				(font
					(size 1.27 1.27)
				)
				(justify left)
			)
		)
		(property "Value" "R_47k_0402"
			(at 116.84 257.81 0)
			(effects
				(font
					(size 1.27 1.27)
					(thickness 0.15)
				)
				(justify left bottom)
				(hide yes)
			)
		)
		(property "Footprint" "antmicro-footprints:R_0402_1005Metric"
			(at 114.3 257.81 0)
			(effects
				(font
					(size 1.27 1.27)
					(thickness 0.15)
				)
				(justify left bottom)
				(hide yes)
			)
		)
		(property "Datasheet" "https://www.bourns.com/docs/product-datasheets/cr.pdf"
			(at 111.76 257.81 0)
			(effects
				(font
					(size 1.27 1.27)
					(thickness 0.15)
				)
				(justify left bottom)
				(hide yes)
			)
		)
		(property "Description" "SMD Chip Resistor, 47 kohm, ± 1%, 62.5 mW, 0402 [1005 Metric], Thick Film, General Purpose"
			(at 129.54 237.49 0)
			(effects
				(font
					(size 1.27 1.27)
				)
				(hide yes)
			)
		)
		(property "Manufacturer" "Bourns"
			(at 106.68 257.81 0)
			(effects
				(font
					(size 1.27 1.27)
					(thickness 0.15)
				)
				(justify left bottom)
				(hide yes)
			)
		)
		(property "MPN" "CR0402-FX-4702GLF"
			(at 109.22 257.81 0)
			(effects
				(font
					(size 1.27 1.27)
					(thickness 0.15)
				)
				(justify left bottom)
				(hide yes)
			)
		)
		(property "Val" "47k"
			(at 128.27 242.57 0)
			(effects
				(font
					(size 1.27 1.27)
					(thickness 0.15)
				)
				(justify left)
			)
		)
		(property "License" "Apache-2.0"
			(at 104.14 257.81 0)
			(effects
				(font
					(size 1.27 1.27)
					(thickness 0.15)
				)
				(justify left bottom)
				(hide yes)
			)
		)
		(property "Author" "Antmicro"
			(at 101.6 257.81 0)
			(effects
				(font
					(size 1.27 1.27)
					(thickness 0.15)
				)
				(justify left bottom)
				(hide yes)
			)
		)
		(property "Tolerance" "1%"
			(at 119.38 257.81 0)
			(effects
				(font
					(size 1.27 1.27)
				)
				(justify left bottom)
				(hide yes)
			)
		)
		(pin "1"
		)
		(pin "2"
		)
		(instances
			(project "artix-dc-scm"
				(path ""
					(reference "R123")
					(unit 1)
				)
			)
		)
	)
	(symbol
		(lib_id "antmicroResistors0402:R_47k_0402")
		(at 133.35 237.49 270)
		(unit 1)
		(exclude_from_sim no)
		(in_bom yes)
		(on_board yes)
		(dnp no)
		(property "Reference" "R124"
			(at 132.08 232.41 0)
			(effects
				(font
					(size 1.27 1.27)
				)
				(justify left)
			)
		)
		(property "Value" "R_47k_0402"
			(at 120.65 257.81 0)
			(effects
				(font
					(size 1.27 1.27)
					(thickness 0.15)
				)
				(justify left bottom)
				(hide yes)
			)
		)
		(property "Footprint" "antmicro-footprints:R_0402_1005Metric"
			(at 118.11 257.81 0)
			(effects
				(font
					(size 1.27 1.27)
					(thickness 0.15)
				)
				(justify left bottom)
				(hide yes)
			)
		)
		(property "Datasheet" "https://www.bourns.com/docs/product-datasheets/cr.pdf"
			(at 115.57 257.81 0)
			(effects
				(font
					(size 1.27 1.27)
					(thickness 0.15)
				)
				(justify left bottom)
				(hide yes)
			)
		)
		(property "Description" "SMD Chip Resistor, 47 kohm, ± 1%, 62.5 mW, 0402 [1005 Metric], Thick Film, General Purpose"
			(at 133.35 237.49 0)
			(effects
				(font
					(size 1.27 1.27)
				)
				(hide yes)
			)
		)
		(property "Manufacturer" "Bourns"
			(at 110.49 257.81 0)
			(effects
				(font
					(size 1.27 1.27)
					(thickness 0.15)
				)
				(justify left bottom)
				(hide yes)
			)
		)
		(property "MPN" "CR0402-FX-4702GLF"
			(at 113.03 257.81 0)
			(effects
				(font
					(size 1.27 1.27)
					(thickness 0.15)
				)
				(justify left bottom)
				(hide yes)
			)
		)
		(property "Val" "47k"
			(at 132.08 242.57 0)
			(effects
				(font
					(size 1.27 1.27)
					(thickness 0.15)
				)
				(justify left)
			)
		)
		(property "License" "Apache-2.0"
			(at 107.95 257.81 0)
			(effects
				(font
					(size 1.27 1.27)
					(thickness 0.15)
				)
				(justify left bottom)
				(hide yes)
			)
		)
		(property "Author" "Antmicro"
			(at 105.41 257.81 0)
			(effects
				(font
					(size 1.27 1.27)
					(thickness 0.15)
				)
				(justify left bottom)
				(hide yes)
			)
		)
		(property "Tolerance" "1%"
			(at 123.19 257.81 0)
			(effects
				(font
					(size 1.27 1.27)
				)
				(justify left bottom)
				(hide yes)
			)
		)
		(pin "1"
		)
		(pin "2"
		)
		(instances
			(project "artix-dc-scm"
				(path ""
					(reference "R124")
					(unit 1)
				)
			)
		)
	)
	(symbol
		(lib_id "antmicroResistors0402:R_47k_0402")
		(at 137.16 237.49 270)
		(unit 1)
		(exclude_from_sim no)
		(in_bom yes)
		(on_board yes)
		(dnp no)
		(property "Reference" "R125"
			(at 135.89 232.41 0)
			(effects
				(font
					(size 1.27 1.27)
				)
				(justify left)
			)
		)
		(property "Value" "R_47k_0402"
			(at 124.46 257.81 0)
			(effects
				(font
					(size 1.27 1.27)
					(thickness 0.15)
				)
				(justify left bottom)
				(hide yes)
			)
		)
		(property "Footprint" "antmicro-footprints:R_0402_1005Metric"
			(at 121.92 257.81 0)
			(effects
				(font
					(size 1.27 1.27)
					(thickness 0.15)
				)
				(justify left bottom)
				(hide yes)
			)
		)
		(property "Datasheet" "https://www.bourns.com/docs/product-datasheets/cr.pdf"
			(at 119.38 257.81 0)
			(effects
				(font
					(size 1.27 1.27)
					(thickness 0.15)
				)
				(justify left bottom)
				(hide yes)
			)
		)
		(property "Description" "SMD Chip Resistor, 47 kohm, ± 1%, 62.5 mW, 0402 [1005 Metric], Thick Film, General Purpose"
			(at 137.16 237.49 0)
			(effects
				(font
					(size 1.27 1.27)
				)
				(hide yes)
			)
		)
		(property "Manufacturer" "Bourns"
			(at 114.3 257.81 0)
			(effects
				(font
					(size 1.27 1.27)
					(thickness 0.15)
				)
				(justify left bottom)
				(hide yes)
			)
		)
		(property "MPN" "CR0402-FX-4702GLF"
			(at 116.84 257.81 0)
			(effects
				(font
					(size 1.27 1.27)
					(thickness 0.15)
				)
				(justify left bottom)
				(hide yes)
			)
		)
		(property "Val" "47k"
			(at 135.89 242.57 0)
			(effects
				(font
					(size 1.27 1.27)
					(thickness 0.15)
				)
				(justify left)
			)
		)
		(property "License" "Apache-2.0"
			(at 111.76 257.81 0)
			(effects
				(font
					(size 1.27 1.27)
					(thickness 0.15)
				)
				(justify left bottom)
				(hide yes)
			)
		)
		(property "Author" "Antmicro"
			(at 109.22 257.81 0)
			(effects
				(font
					(size 1.27 1.27)
					(thickness 0.15)
				)
				(justify left bottom)
				(hide yes)
			)
		)
		(property "Tolerance" "1%"
			(at 127 257.81 0)
			(effects
				(font
					(size 1.27 1.27)
				)
				(justify left bottom)
				(hide yes)
			)
		)
		(pin "1"
		)
		(pin "2"
		)
		(instances
			(project "artix-dc-scm"
				(path ""
					(reference "R125")
					(unit 1)
				)
			)
		)
	)
	(symbol
		(lib_id "antmicroInterfaceControllers:USB3300-EZK-TR")
		(at 358.14 137.16 0)
		(unit 1)
		(exclude_from_sim no)
		(in_bom yes)
		(on_board yes)
		(dnp no)
		(fields_autoplaced yes)
		(property "Reference" "U18"
			(at 370.205 129.54 0)
			(effects
				(font
					(size 1.27 1.27)
				)
			)
		)
		(property "Value" "USB3300-EZK-TR"
			(at 370.205 132.08 0)
			(effects
				(font
					(size 1.27 1.27)
				)
			)
		)
		(property "Footprint" "antmicro-footprints:QFN-32-1EP_5x5mm"
			(at 396.24 144.78 0)
			(effects
				(font
					(size 1.27 1.27)
					(thickness 0.15)
				)
				(justify left bottom)
				(hide yes)
			)
		)
		(property "Datasheet" "https://ww1.microchip.com/downloads/en/DeviceDoc/00001783C.pdf"
			(at 396.24 147.32 0)
			(effects
				(font
					(size 1.27 1.27)
					(thickness 0.15)
				)
				(justify left bottom)
				(hide yes)
			)
		)
		(property "Description" "USB Interface, USB Host Controller, USB 2.0 OTG, 3 V, 3.6 V, VQFN, 32 Pins"
			(at 358.14 137.16 0)
			(effects
				(font
					(size 1.27 1.27)
				)
				(hide yes)
			)
		)
		(property "Manufacturer" "Microchip Technology"
			(at 396.24 149.86 0)
			(effects
				(font
					(size 1.27 1.27)
					(thickness 0.15)
				)
				(justify left bottom)
				(hide yes)
			)
		)
		(property "MPN" "USB3300-EZK-TR"
			(at 396.24 152.4 0)
			(effects
				(font
					(size 1.27 1.27)
					(thickness 0.15)
				)
				(justify left bottom)
				(hide yes)
			)
		)
		(property "Author" "Antmicro"
			(at 396.24 154.94 0)
			(effects
				(font
					(size 1.27 1.27)
					(thickness 0.15)
				)
				(justify left bottom)
				(hide yes)
			)
		)
		(property "License" "Apache-2.0"
			(at 396.24 157.48 0)
			(effects
				(font
					(size 1.27 1.27)
					(thickness 0.15)
				)
				(justify left bottom)
				(hide yes)
			)
		)
		(pin "1"
		)
		(pin "10"
		)
		(pin "11"
		)
		(pin "12"
		)
		(pin "13"
		)
		(pin "14"
		)
		(pin "15"
		)
		(pin "16"
		)
		(pin "17"
		)
		(pin "18"
		)
		(pin "19"
		)
		(pin "2"
		)
		(pin "20"
		)
		(pin "21"
		)
		(pin "22"
		)
		(pin "23"
		)
		(pin "24"
		)
		(pin "25"
		)
		(pin "26"
		)
		(pin "27"
		)
		(pin "28"
		)
		(pin "29"
		)
		(pin "3"
		)
		(pin "30"
		)
		(pin "31"
		)
		(pin "32"
		)
		(pin "33"
		)
		(pin "4"
		)
		(pin "5"
		)
		(pin "6"
		)
		(pin "7"
		)
		(pin "8"
		)
		(pin "9"
		)
		(instances
			(project "artix-dc-scm"
				(path ""
					(reference "U18")
					(unit 1)
				)
			)
		)
	)
	(symbol
		(lib_id "antmicroResistors0402:R_1k_0402")
		(at 347.98 154.94 0)
		(unit 1)
		(exclude_from_sim no)
		(in_bom yes)
		(on_board yes)
		(dnp no)
		(property "Reference" "R8"
			(at 353.06 153.67 0)
			(effects
				(font
					(size 1.27 1.27)
				)
				(justify left)
			)
		)
		(property "Value" "R_1k_0402"
			(at 368.3 167.64 0)
			(effects
				(font
					(size 1.27 1.27)
					(thickness 0.15)
				)
				(justify left bottom)
				(hide yes)
			)
		)
		(property "Footprint" "antmicro-footprints:R_0402_1005Metric"
			(at 368.3 170.18 0)
			(effects
				(font
					(size 1.27 1.27)
					(thickness 0.15)
				)
				(justify left bottom)
				(hide yes)
			)
		)
		(property "Datasheet" "https://www.bourns.com/docs/product-datasheets/cr.pdf"
			(at 368.3 172.72 0)
			(effects
				(font
					(size 1.27 1.27)
					(thickness 0.15)
				)
				(justify left bottom)
				(hide yes)
			)
		)
		(property "Description" "SMD Chip Resistor, 1 kohm, ± 1%, 63 mW, 0402 [1005 Metric], Thick Film, General Purpose"
			(at 347.98 154.94 0)
			(effects
				(font
					(size 1.27 1.27)
				)
				(hide yes)
			)
		)
		(property "Manufacturer" "Bourns"
			(at 368.3 177.8 0)
			(effects
				(font
					(size 1.27 1.27)
					(thickness 0.15)
				)
				(justify left bottom)
				(hide yes)
			)
		)
		(property "MPN" "CR0402-FX-1001GLF"
			(at 368.3 175.26 0)
			(effects
				(font
					(size 1.27 1.27)
					(thickness 0.15)
				)
				(justify left bottom)
				(hide yes)
			)
		)
		(property "Val" "1k"
			(at 346.71 153.67 0)
			(effects
				(font
					(size 1.27 1.27)
					(thickness 0.15)
				)
			)
		)
		(property "License" "Apache-2.0"
			(at 368.3 180.34 0)
			(effects
				(font
					(size 1.27 1.27)
					(thickness 0.15)
				)
				(justify left bottom)
				(hide yes)
			)
		)
		(property "Author" "Antmicro"
			(at 368.3 182.88 0)
			(effects
				(font
					(size 1.27 1.27)
					(thickness 0.15)
				)
				(justify left bottom)
				(hide yes)
			)
		)
		(property "Tolerance" "1%"
			(at 368.3 165.1 0)
			(effects
				(font
					(size 1.27 1.27)
				)
				(justify left bottom)
				(hide yes)
			)
		)
		(pin "1"
		)
		(pin "2"
		)
		(instances
			(project "artix-dc-scm"
				(path ""
					(reference "R8")
					(unit 1)
				)
			)
		)
	)
	(symbol
		(lib_id "antmicroOscillators:Oscillator_24MHz_ASEMB")
		(at 323.85 82.55 0)
		(unit 1)
		(exclude_from_sim no)
		(in_bom yes)
		(on_board yes)
		(dnp no)
		(fields_autoplaced yes)
		(property "Reference" "U24"
			(at 333.375 74.93 0)
			(effects
				(font
					(size 1.27 1.27)
				)
			)
		)
		(property "Value" "Oscillator_24MHz_ASEMB"
			(at 333.375 77.47 0)
			(effects
				(font
					(size 1.27 1.27)
				)
			)
		)
		(property "Footprint" "antmicro-footprints:Oscillator_SMD_Abracon_ASEMB_3.2x2.5mm"
			(at 355.6 91.44 0)
			(effects
				(font
					(size 1.27 1.27)
					(thickness 0.15)
				)
				(justify left bottom)
				(hide yes)
			)
		)
		(property "Datasheet" "https://abracon.com/Oscillators/ASEMB.pdf"
			(at 355.6 93.98 0)
			(effects
				(font
					(size 1.27 1.27)
					(thickness 0.15)
				)
				(justify left bottom)
				(hide yes)
			)
		)
		(property "Description" "MEMS Oscillator, Clock, Pure Silicon&trade;, 24 MHz, SMD, 3.2mm x 2.5mm, 50 ppm, 3.3 V, ASEMB, LVCMOS"
			(at 323.85 82.55 0)
			(effects
				(font
					(size 1.27 1.27)
				)
				(hide yes)
			)
		)
		(property "MPN" "ASEMB-24.000MHZ-LC-T"
			(at 333.375 77.47 0)
			(effects
				(font
					(size 1.27 1.27)
					(thickness 0.15)
				)
				(hide yes)
			)
		)
		(property "Manufacturer" "Abracon"
			(at 355.6 99.06 0)
			(effects
				(font
					(size 1.27 1.27)
					(thickness 0.15)
				)
				(justify left bottom)
				(hide yes)
			)
		)
		(property "Author" "Antmicro"
			(at 355.6 101.6 0)
			(effects
				(font
					(size 1.27 1.27)
					(thickness 0.15)
				)
				(justify left bottom)
				(hide yes)
			)
		)
		(property "License" "Apache-2.0"
			(at 355.6 104.14 0)
			(effects
				(font
					(size 1.27 1.27)
					(thickness 0.15)
				)
				(justify left bottom)
				(hide yes)
			)
		)
		(property "Val" "24 MHz"
			(at 333.375 77.47 0)
			(effects
				(font
					(size 1.27 1.27)
				)
				(hide yes)
			)
		)
		(pin "1"
		)
		(pin "2"
		)
		(pin "3"
		)
		(pin "4"
		)
		(instances
			(project "artix-dc-scm"
				(path ""
					(reference "U24")
					(unit 1)
				)
			)
		)
	)
	(symbol
		(lib_id "antmicroResistors0402:R_22R_0402")
		(at 99.06 252.73 0)
		(unit 1)
		(exclude_from_sim no)
		(in_bom yes)
		(on_board yes)
		(dnp no)
		(property "Reference" "R9"
			(at 101.6 247.65 0)
			(effects
				(font
					(size 1.27 1.27)
				)
			)
		)
		(property "Value" "R_22R_0402"
			(at 119.38 265.43 0)
			(effects
				(font
					(size 1.27 1.27)
					(thickness 0.15)
				)
				(justify left bottom)
				(hide yes)
			)
		)
		(property "Footprint" "antmicro-footprints:R_0402_1005Metric"
			(at 119.38 267.97 0)
			(effects
				(font
					(size 1.27 1.27)
					(thickness 0.15)
				)
				(justify left bottom)
				(hide yes)
			)
		)
		(property "Datasheet" "https://www.bourns.com/docs/product-datasheets/cr.pdf"
			(at 119.38 270.51 0)
			(effects
				(font
					(size 1.27 1.27)
					(thickness 0.15)
				)
				(justify left bottom)
				(hide yes)
			)
		)
		(property "Description" "SMD Chip Resistor, 22 ohm, ± 1%, 62.5 mW, 0402 [1005 Metric], Thick Film, General Purpose"
			(at 99.06 252.73 0)
			(effects
				(font
					(size 1.27 1.27)
				)
				(hide yes)
			)
		)
		(property "Manufacturer" "Bourns"
			(at 119.38 275.59 0)
			(effects
				(font
					(size 1.27 1.27)
					(thickness 0.15)
				)
				(justify left bottom)
				(hide yes)
			)
		)
		(property "MPN" "CR0402-FX-22R0GLF"
			(at 119.38 273.05 0)
			(effects
				(font
					(size 1.27 1.27)
					(thickness 0.15)
				)
				(justify left bottom)
				(hide yes)
			)
		)
		(property "Val" "22R"
			(at 101.6 250.19 0)
			(effects
				(font
					(size 1.27 1.27)
					(thickness 0.15)
				)
			)
		)
		(property "License" "Apache-2.0"
			(at 119.38 278.13 0)
			(effects
				(font
					(size 1.27 1.27)
					(thickness 0.15)
				)
				(justify left bottom)
				(hide yes)
			)
		)
		(property "Author" "Antmicro"
			(at 119.38 280.67 0)
			(effects
				(font
					(size 1.27 1.27)
					(thickness 0.15)
				)
				(justify left bottom)
				(hide yes)
			)
		)
		(property "Tolerance" "1%"
			(at 119.38 262.89 0)
			(effects
				(font
					(size 1.27 1.27)
				)
				(justify left bottom)
				(hide yes)
			)
		)
		(pin "1"
		)
		(pin "2"
		)
		(instances
			(project "artix-dc-scm"
				(path ""
					(reference "R9")
					(unit 1)
				)
			)
		)
	)
	(symbol
		(lib_id "antmicropower:GND")
		(at 322.58 90.17 0)
		(unit 1)
		(exclude_from_sim no)
		(in_bom yes)
		(on_board yes)
		(dnp no)
		(property "Reference" "#PWR0164"
			(at 322.58 96.52 0)
			(effects
				(font
					(size 1.27 1.27)
				)
				(hide yes)
			)
		)
		(property "Value" "GND"
			(at 322.58 93.98 0)
			(effects
				(font
					(size 1.27 1.27)
				)
			)
		)
		(property "Footprint" ""
			(at 322.58 90.17 0)
			(effects
				(font
					(size 1.27 1.27)
				)
				(hide yes)
			)
		)
		(property "Datasheet" ""
			(at 322.58 90.17 0)
			(effects
				(font
					(size 1.27 1.27)
				)
				(hide yes)
			)
		)
		(property "Description" ""
			(at 322.58 90.17 0)
			(effects
				(font
					(size 1.27 1.27)
				)
				(hide yes)
			)
		)
		(property "Author" "Antmicro"
			(at 331.47 97.79 0)
			(effects
				(font
					(size 1.27 1.27)
					(thickness 0.15)
				)
				(justify left bottom)
				(hide yes)
			)
		)
		(property "License" "Apache-2.0"
			(at 331.47 100.33 0)
			(effects
				(font
					(size 1.27 1.27)
					(thickness 0.15)
				)
				(justify left bottom)
				(hide yes)
			)
		)
		(pin "1"
		)
		(instances
			(project "artix-dc-scm"
				(path ""
					(reference "#PWR0164")
					(unit 1)
				)
			)
		)
	)
	(symbol
		(lib_id "antmicroTestPoints:TP_1mm_SMD")
		(at 76.2 265.43 180)
		(unit 1)
		(exclude_from_sim no)
		(in_bom no)
		(on_board yes)
		(dnp no)
		(property "Reference" "TP3"
			(at 73.025 267.97 0)
			(effects
				(font
					(size 1.27 1.27)
				)
			)
		)
		(property "Value" "TP_1mm_SMD"
			(at 76.2 262.89 0)
			(effects
				(font
					(size 1.27 1.27)
				)
				(hide yes)
			)
		)
		(property "Footprint" "antmicro-footprints:TP_SMD_1mm"
			(at 60.96 255.27 0)
			(effects
				(font
					(size 1.27 1.27)
					(thickness 0.15)
				)
				(justify left bottom)
				(hide yes)
			)
		)
		(property "Datasheet" ""
			(at 60.96 252.73 0)
			(effects
				(font
					(size 1.27 1.27)
					(thickness 0.15)
				)
				(justify left bottom)
				(hide yes)
			)
		)
		(property "Description" "Test point 1mm SMD"
			(at 76.2 265.43 0)
			(effects
				(font
					(size 1.27 1.27)
				)
				(hide yes)
			)
		)
		(property "MPN" ""
			(at 76.2 265.43 0)
			(effects
				(font
					(size 1.27 1.27)
				)
				(hide yes)
			)
		)
		(property "Manufacturer" ""
			(at 76.2 265.43 0)
			(effects
				(font
					(size 1.27 1.27)
				)
				(hide yes)
			)
		)
		(property "Author" "Antmicro"
			(at 60.96 250.19 0)
			(effects
				(font
					(size 1.27 1.27)
					(thickness 0.15)
				)
				(justify left bottom)
				(hide yes)
			)
		)
		(property "License" "Apache-2.0"
			(at 60.96 247.65 0)
			(effects
				(font
					(size 1.27 1.27)
					(thickness 0.15)
				)
				(justify left bottom)
				(hide yes)
			)
		)
		(pin "1"
		)
		(instances
			(project "artix-dc-scm"
				(path ""
					(reference "TP3")
					(unit 1)
				)
			)
		)
	)
	(symbol
		(lib_id "antmicroCapacitors0402:C_100n_0402")
		(at 341.63 44.45 90)
		(unit 1)
		(exclude_from_sim no)
		(in_bom yes)
		(on_board yes)
		(dnp no)
		(property "Reference" "C10"
			(at 342.265 40.005 90)
			(effects
				(font
					(size 1.27 1.27)
				)
				(justify right)
			)
		)
		(property "Value" "C_100n_0402"
			(at 351.79 24.13 0)
			(effects
				(font
					(size 1.27 1.27)
					(thickness 0.15)
				)
				(justify left bottom)
				(hide yes)
			)
		)
		(property "Footprint" "antmicro-footprints:C_0402_1005Metric"
			(at 354.33 24.13 0)
			(effects
				(font
					(size 1.27 1.27)
					(thickness 0.15)
				)
				(justify left bottom)
				(hide yes)
			)
		)
		(property "Datasheet" "https://www.murata.com/products/productdetail?partno=GRM155R61H104KE14%23"
			(at 356.87 24.13 0)
			(effects
				(font
					(size 1.27 1.27)
					(thickness 0.15)
				)
				(justify left bottom)
				(hide yes)
			)
		)
		(property "Description" "SMD Multilayer Ceramic Capacitor, 0.1 µF, 50 V, 0402 [1005 Metric], ± 10%, X5R, GRM Series"
			(at 341.63 44.45 0)
			(effects
				(font
					(size 1.27 1.27)
				)
				(hide yes)
			)
		)
		(property "Manufacturer" "Murata"
			(at 361.95 24.13 0)
			(effects
				(font
					(size 1.27 1.27)
					(thickness 0.15)
				)
				(justify left bottom)
				(hide yes)
			)
		)
		(property "MPN" "GRM155R61H104KE14D"
			(at 359.41 24.13 0)
			(effects
				(font
					(size 1.27 1.27)
					(thickness 0.15)
				)
				(justify left bottom)
				(hide yes)
			)
		)
		(property "Val" "100n"
			(at 342.265 43.815 90)
			(effects
				(font
					(size 1.27 1.27)
					(thickness 0.15)
				)
				(justify right)
			)
		)
		(property "License" "Apache-2.0"
			(at 364.49 24.13 0)
			(effects
				(font
					(size 1.27 1.27)
					(thickness 0.15)
				)
				(justify left bottom)
				(hide yes)
			)
		)
		(property "Author" "Antmicro"
			(at 367.03 24.13 0)
			(effects
				(font
					(size 1.27 1.27)
					(thickness 0.15)
				)
				(justify left bottom)
				(hide yes)
			)
		)
		(property "Voltage" "50V"
			(at 369.57 24.13 0)
			(effects
				(font
					(size 1.27 1.27)
				)
				(justify left bottom)
				(hide yes)
			)
		)
		(property "Dielectric" "X5R"
			(at 372.11 24.13 0)
			(effects
				(font
					(size 1.27 1.27)
				)
				(justify left bottom)
				(hide yes)
			)
		)
		(pin "1"
		)
		(pin "2"
		)
		(instances
			(project "artix-dc-scm"
				(path ""
					(reference "C10")
					(unit 1)
				)
			)
		)
	)
	(symbol
		(lib_id "antmicroCapacitors0402:C_100n_0402")
		(at 334.01 44.45 90)
		(unit 1)
		(exclude_from_sim no)
		(in_bom yes)
		(on_board yes)
		(dnp no)
		(property "Reference" "C11"
			(at 334.645 40.005 90)
			(effects
				(font
					(size 1.27 1.27)
				)
				(justify right)
			)
		)
		(property "Value" "C_100n_0402"
			(at 344.17 24.13 0)
			(effects
				(font
					(size 1.27 1.27)
					(thickness 0.15)
				)
				(justify left bottom)
				(hide yes)
			)
		)
		(property "Footprint" "antmicro-footprints:C_0402_1005Metric"
			(at 346.71 24.13 0)
			(effects
				(font
					(size 1.27 1.27)
					(thickness 0.15)
				)
				(justify left bottom)
				(hide yes)
			)
		)
		(property "Datasheet" "https://www.murata.com/products/productdetail?partno=GRM155R61H104KE14%23"
			(at 349.25 24.13 0)
			(effects
				(font
					(size 1.27 1.27)
					(thickness 0.15)
				)
				(justify left bottom)
				(hide yes)
			)
		)
		(property "Description" "SMD Multilayer Ceramic Capacitor, 0.1 µF, 50 V, 0402 [1005 Metric], ± 10%, X5R, GRM Series"
			(at 334.01 44.45 0)
			(effects
				(font
					(size 1.27 1.27)
				)
				(hide yes)
			)
		)
		(property "Manufacturer" "Murata"
			(at 354.33 24.13 0)
			(effects
				(font
					(size 1.27 1.27)
					(thickness 0.15)
				)
				(justify left bottom)
				(hide yes)
			)
		)
		(property "MPN" "GRM155R61H104KE14D"
			(at 351.79 24.13 0)
			(effects
				(font
					(size 1.27 1.27)
					(thickness 0.15)
				)
				(justify left bottom)
				(hide yes)
			)
		)
		(property "Val" "100n"
			(at 334.645 43.815 90)
			(effects
				(font
					(size 1.27 1.27)
					(thickness 0.15)
				)
				(justify right)
			)
		)
		(property "License" "Apache-2.0"
			(at 356.87 24.13 0)
			(effects
				(font
					(size 1.27 1.27)
					(thickness 0.15)
				)
				(justify left bottom)
				(hide yes)
			)
		)
		(property "Author" "Antmicro"
			(at 359.41 24.13 0)
			(effects
				(font
					(size 1.27 1.27)
					(thickness 0.15)
				)
				(justify left bottom)
				(hide yes)
			)
		)
		(property "Voltage" "50V"
			(at 361.95 24.13 0)
			(effects
				(font
					(size 1.27 1.27)
				)
				(justify left bottom)
				(hide yes)
			)
		)
		(property "Dielectric" "X5R"
			(at 364.49 24.13 0)
			(effects
				(font
					(size 1.27 1.27)
				)
				(justify left bottom)
				(hide yes)
			)
		)
		(pin "1"
		)
		(pin "2"
		)
		(instances
			(project "artix-dc-scm"
				(path ""
					(reference "C11")
					(unit 1)
				)
			)
		)
	)
	(symbol
		(lib_id "antmicroCapacitors0402:C_100n_0402")
		(at 317.5 44.45 90)
		(unit 1)
		(exclude_from_sim no)
		(in_bom yes)
		(on_board yes)
		(dnp no)
		(property "Reference" "C13"
			(at 318.135 40.005 90)
			(effects
				(font
					(size 1.27 1.27)
				)
				(justify right)
			)
		)
		(property "Value" "C_100n_0402"
			(at 327.66 24.13 0)
			(effects
				(font
					(size 1.27 1.27)
					(thickness 0.15)
				)
				(justify left bottom)
				(hide yes)
			)
		)
		(property "Footprint" "antmicro-footprints:C_0402_1005Metric"
			(at 330.2 24.13 0)
			(effects
				(font
					(size 1.27 1.27)
					(thickness 0.15)
				)
				(justify left bottom)
				(hide yes)
			)
		)
		(property "Datasheet" "https://www.murata.com/products/productdetail?partno=GRM155R61H104KE14%23"
			(at 332.74 24.13 0)
			(effects
				(font
					(size 1.27 1.27)
					(thickness 0.15)
				)
				(justify left bottom)
				(hide yes)
			)
		)
		(property "Description" "SMD Multilayer Ceramic Capacitor, 0.1 µF, 50 V, 0402 [1005 Metric], ± 10%, X5R, GRM Series"
			(at 317.5 44.45 0)
			(effects
				(font
					(size 1.27 1.27)
				)
				(hide yes)
			)
		)
		(property "Manufacturer" "Murata"
			(at 337.82 24.13 0)
			(effects
				(font
					(size 1.27 1.27)
					(thickness 0.15)
				)
				(justify left bottom)
				(hide yes)
			)
		)
		(property "MPN" "GRM155R61H104KE14D"
			(at 335.28 24.13 0)
			(effects
				(font
					(size 1.27 1.27)
					(thickness 0.15)
				)
				(justify left bottom)
				(hide yes)
			)
		)
		(property "Val" "100n"
			(at 318.135 43.815 90)
			(effects
				(font
					(size 1.27 1.27)
					(thickness 0.15)
				)
				(justify right)
			)
		)
		(property "License" "Apache-2.0"
			(at 340.36 24.13 0)
			(effects
				(font
					(size 1.27 1.27)
					(thickness 0.15)
				)
				(justify left bottom)
				(hide yes)
			)
		)
		(property "Author" "Antmicro"
			(at 342.9 24.13 0)
			(effects
				(font
					(size 1.27 1.27)
					(thickness 0.15)
				)
				(justify left bottom)
				(hide yes)
			)
		)
		(property "Voltage" "50V"
			(at 345.44 24.13 0)
			(effects
				(font
					(size 1.27 1.27)
				)
				(justify left bottom)
				(hide yes)
			)
		)
		(property "Dielectric" "X5R"
			(at 347.98 24.13 0)
			(effects
				(font
					(size 1.27 1.27)
				)
				(justify left bottom)
				(hide yes)
			)
		)
		(pin "1"
		)
		(pin "2"
		)
		(instances
			(project "artix-dc-scm"
				(path ""
					(reference "C13")
					(unit 1)
				)
			)
		)
	)
	(symbol
		(lib_id "antmicroCapacitors0402:C_100n_0402")
		(at 326.39 44.45 90)
		(unit 1)
		(exclude_from_sim no)
		(in_bom yes)
		(on_board yes)
		(dnp no)
		(property "Reference" "C19"
			(at 327.025 40.005 90)
			(effects
				(font
					(size 1.27 1.27)
				)
				(justify right)
			)
		)
		(property "Value" "C_100n_0402"
			(at 336.55 24.13 0)
			(effects
				(font
					(size 1.27 1.27)
					(thickness 0.15)
				)
				(justify left bottom)
				(hide yes)
			)
		)
		(property "Footprint" "antmicro-footprints:C_0402_1005Metric"
			(at 339.09 24.13 0)
			(effects
				(font
					(size 1.27 1.27)
					(thickness 0.15)
				)
				(justify left bottom)
				(hide yes)
			)
		)
		(property "Datasheet" "https://www.murata.com/products/productdetail?partno=GRM155R61H104KE14%23"
			(at 341.63 24.13 0)
			(effects
				(font
					(size 1.27 1.27)
					(thickness 0.15)
				)
				(justify left bottom)
				(hide yes)
			)
		)
		(property "Description" "SMD Multilayer Ceramic Capacitor, 0.1 µF, 50 V, 0402 [1005 Metric], ± 10%, X5R, GRM Series"
			(at 326.39 44.45 0)
			(effects
				(font
					(size 1.27 1.27)
				)
				(hide yes)
			)
		)
		(property "Manufacturer" "Murata"
			(at 346.71 24.13 0)
			(effects
				(font
					(size 1.27 1.27)
					(thickness 0.15)
				)
				(justify left bottom)
				(hide yes)
			)
		)
		(property "MPN" "GRM155R61H104KE14D"
			(at 344.17 24.13 0)
			(effects
				(font
					(size 1.27 1.27)
					(thickness 0.15)
				)
				(justify left bottom)
				(hide yes)
			)
		)
		(property "Val" "100n"
			(at 327.025 43.815 90)
			(effects
				(font
					(size 1.27 1.27)
					(thickness 0.15)
				)
				(justify right)
			)
		)
		(property "License" "Apache-2.0"
			(at 349.25 24.13 0)
			(effects
				(font
					(size 1.27 1.27)
					(thickness 0.15)
				)
				(justify left bottom)
				(hide yes)
			)
		)
		(property "Author" "Antmicro"
			(at 351.79 24.13 0)
			(effects
				(font
					(size 1.27 1.27)
					(thickness 0.15)
				)
				(justify left bottom)
				(hide yes)
			)
		)
		(property "Voltage" "50V"
			(at 354.33 24.13 0)
			(effects
				(font
					(size 1.27 1.27)
				)
				(justify left bottom)
				(hide yes)
			)
		)
		(property "Dielectric" "X5R"
			(at 356.87 24.13 0)
			(effects
				(font
					(size 1.27 1.27)
				)
				(justify left bottom)
				(hide yes)
			)
		)
		(pin "1"
		)
		(pin "2"
		)
		(instances
			(project "artix-dc-scm"
				(path ""
					(reference "C19")
					(unit 1)
				)
			)
		)
	)
	(symbol
		(lib_id "antmicroCapacitors0402:C_4u7_0402")
		(at 309.88 44.45 90)
		(unit 1)
		(exclude_from_sim no)
		(in_bom yes)
		(on_board yes)
		(dnp no)
		(property "Reference" "C23"
			(at 310.515 40.005 90)
			(effects
				(font
					(size 1.27 1.27)
				)
				(justify right)
			)
		)
		(property "Value" "C_4u7_0402"
			(at 320.04 24.13 0)
			(effects
				(font
					(size 1.27 1.27)
					(thickness 0.15)
				)
				(justify left bottom)
				(hide yes)
			)
		)
		(property "Footprint" "antmicro-footprints:C_0402_1005Metric"
			(at 322.58 24.13 0)
			(effects
				(font
					(size 1.27 1.27)
					(thickness 0.15)
				)
				(justify left bottom)
				(hide yes)
			)
		)
		(property "Datasheet" "https://www.murata.com/products/productdetail?partno=GRM155R61A475MEAA%23"
			(at 325.12 24.13 0)
			(effects
				(font
					(size 1.27 1.27)
					(thickness 0.15)
				)
				(justify left bottom)
				(hide yes)
			)
		)
		(property "Description" "SMD Multilayer Ceramic Capacitor, 4.7 µF, 10 V, 0402 [1005 Metric], ± 20%, X5R, GRM Series"
			(at 309.88 44.45 0)
			(effects
				(font
					(size 1.27 1.27)
				)
				(hide yes)
			)
		)
		(property "Manufacturer" "Murata"
			(at 330.2 24.13 0)
			(effects
				(font
					(size 1.27 1.27)
					(thickness 0.15)
				)
				(justify left bottom)
				(hide yes)
			)
		)
		(property "MPN" "GRM155R61A475MEAAD"
			(at 327.66 24.13 0)
			(effects
				(font
					(size 1.27 1.27)
					(thickness 0.15)
				)
				(justify left bottom)
				(hide yes)
			)
		)
		(property "Val" "4u7"
			(at 310.515 43.815 90)
			(effects
				(font
					(size 1.27 1.27)
					(thickness 0.15)
				)
				(justify right)
			)
		)
		(property "License" "Apache-2.0"
			(at 332.74 24.13 0)
			(effects
				(font
					(size 1.27 1.27)
					(thickness 0.15)
				)
				(justify left bottom)
				(hide yes)
			)
		)
		(property "Author" "Antmicro"
			(at 335.28 24.13 0)
			(effects
				(font
					(size 1.27 1.27)
					(thickness 0.15)
				)
				(justify left bottom)
				(hide yes)
			)
		)
		(property "Voltage" ""
			(at 337.82 24.13 0)
			(effects
				(font
					(size 1.27 1.27)
				)
				(justify left bottom)
				(hide yes)
			)
		)
		(property "Dielectric" ""
			(at 340.36 24.13 0)
			(effects
				(font
					(size 1.27 1.27)
				)
				(justify left bottom)
				(hide yes)
			)
		)
		(pin "1"
		)
		(pin "2"
		)
		(instances
			(project "artix-dc-scm"
				(path ""
					(reference "C23")
					(unit 1)
				)
			)
		)
	)
	(symbol
		(lib_id "antmicroCapacitors0402:C_100n_0402")
		(at 177.8 214.63 90)
		(unit 1)
		(exclude_from_sim no)
		(in_bom yes)
		(on_board yes)
		(dnp no)
		(property "Reference" "C254"
			(at 178.435 210.185 90)
			(effects
				(font
					(size 1.27 1.27)
				)
				(justify right)
			)
		)
		(property "Value" "C_100n_0402"
			(at 187.96 194.31 0)
			(effects
				(font
					(size 1.27 1.27)
					(thickness 0.15)
				)
				(justify left bottom)
				(hide yes)
			)
		)
		(property "Footprint" "antmicro-footprints:C_0402_1005Metric"
			(at 190.5 194.31 0)
			(effects
				(font
					(size 1.27 1.27)
					(thickness 0.15)
				)
				(justify left bottom)
				(hide yes)
			)
		)
		(property "Datasheet" "https://www.murata.com/products/productdetail?partno=GRM155R61H104KE14%23"
			(at 193.04 194.31 0)
			(effects
				(font
					(size 1.27 1.27)
					(thickness 0.15)
				)
				(justify left bottom)
				(hide yes)
			)
		)
		(property "Description" "SMD Multilayer Ceramic Capacitor, 0.1 µF, 50 V, 0402 [1005 Metric], ± 10%, X5R, GRM Series"
			(at 177.8 214.63 0)
			(effects
				(font
					(size 1.27 1.27)
				)
				(hide yes)
			)
		)
		(property "Manufacturer" "Murata"
			(at 198.12 194.31 0)
			(effects
				(font
					(size 1.27 1.27)
					(thickness 0.15)
				)
				(justify left bottom)
				(hide yes)
			)
		)
		(property "MPN" "GRM155R61H104KE14D"
			(at 195.58 194.31 0)
			(effects
				(font
					(size 1.27 1.27)
					(thickness 0.15)
				)
				(justify left bottom)
				(hide yes)
			)
		)
		(property "Val" "100n"
			(at 178.435 213.995 90)
			(effects
				(font
					(size 1.27 1.27)
					(thickness 0.15)
				)
				(justify right)
			)
		)
		(property "License" "Apache-2.0"
			(at 200.66 194.31 0)
			(effects
				(font
					(size 1.27 1.27)
					(thickness 0.15)
				)
				(justify left bottom)
				(hide yes)
			)
		)
		(property "Author" "Antmicro"
			(at 203.2 194.31 0)
			(effects
				(font
					(size 1.27 1.27)
					(thickness 0.15)
				)
				(justify left bottom)
				(hide yes)
			)
		)
		(property "Voltage" "50V"
			(at 205.74 194.31 0)
			(effects
				(font
					(size 1.27 1.27)
				)
				(justify left bottom)
				(hide yes)
			)
		)
		(property "Dielectric" "X5R"
			(at 208.28 194.31 0)
			(effects
				(font
					(size 1.27 1.27)
				)
				(justify left bottom)
				(hide yes)
			)
		)
		(pin "1"
		)
		(pin "2"
		)
		(instances
			(project "artix-dc-scm"
				(path ""
					(reference "C254")
					(unit 1)
				)
			)
		)
	)
	(symbol
		(lib_id "antmicropower:GND")
		(at 177.8 214.63 0)
		(unit 1)
		(exclude_from_sim no)
		(in_bom yes)
		(on_board yes)
		(dnp no)
		(property "Reference" "#PWR0162"
			(at 177.8 220.98 0)
			(effects
				(font
					(size 1.27 1.27)
				)
				(hide yes)
			)
		)
		(property "Value" "GND"
			(at 177.8 218.44 0)
			(effects
				(font
					(size 1.27 1.27)
				)
			)
		)
		(property "Footprint" ""
			(at 177.8 214.63 0)
			(effects
				(font
					(size 1.27 1.27)
				)
				(hide yes)
			)
		)
		(property "Datasheet" ""
			(at 177.8 214.63 0)
			(effects
				(font
					(size 1.27 1.27)
				)
				(hide yes)
			)
		)
		(property "Description" ""
			(at 177.8 214.63 0)
			(effects
				(font
					(size 1.27 1.27)
				)
				(hide yes)
			)
		)
		(property "Author" "Antmicro"
			(at 186.69 222.25 0)
			(effects
				(font
					(size 1.27 1.27)
					(thickness 0.15)
				)
				(justify left bottom)
				(hide yes)
			)
		)
		(property "License" "Apache-2.0"
			(at 186.69 224.79 0)
			(effects
				(font
					(size 1.27 1.27)
					(thickness 0.15)
				)
				(justify left bottom)
				(hide yes)
			)
		)
		(pin "1"
		)
		(instances
			(project "artix-dc-scm"
				(path ""
					(reference "#PWR0162")
					(unit 1)
				)
			)
		)
	)
	(symbol
		(lib_id "antmicroFPGAChips:XC7A100T-FGG484")
		(at 64.77 44.45 0)
		(unit 5)
		(exclude_from_sim no)
		(in_bom yes)
		(on_board yes)
		(dnp no)
		(property "Reference" "U14"
			(at 78.74 36.83 0)
			(effects
				(font
					(size 1.27 1.27)
				)
				(justify left)
			)
		)
		(property "Value" "XC7A100T-FGG484"
			(at 71.12 39.37 0)
			(effects
				(font
					(size 1.27 1.27)
				)
				(justify left)
			)
		)
		(property "Footprint" "antmicro-footprints:BGA-484_23x23mm_Layout22x22_P1mm_FGG484"
			(at 57.15 44.45 0)
			(effects
				(font
					(size 1.27 1.27)
				)
				(hide yes)
			)
		)
		(property "Datasheet" "https://docs.xilinx.com/v/u/en-US/ds181_Artix_7_Data_Sheet"
			(at 57.15 44.45 0)
			(effects
				(font
					(size 1.27 1.27)
				)
				(hide yes)
			)
		)
		(property "Description" "Artix-7 Field Programmable Gate Array IC 210 324-LFBGA, CSPBGA"
			(at 64.77 44.45 0)
			(effects
				(font
					(size 1.27 1.27)
				)
				(hide yes)
			)
		)
		(property "MPN" "XC7A100T-FGG484"
			(at 64.77 44.45 0)
			(effects
				(font
					(size 1.27 1.27)
				)
				(hide yes)
			)
		)
		(property "Manufacturer" "AMD-Xilinx"
			(at 64.77 44.45 0)
			(effects
				(font
					(size 1.27 1.27)
				)
				(hide yes)
			)
		)
		(property "Author" "Antmicro"
			(at 120.65 62.23 0)
			(effects
				(font
					(size 1.27 1.27)
					(thickness 0.15)
				)
				(justify left bottom)
				(hide yes)
			)
		)
		(property "License" "Apache-2.0"
			(at 120.65 64.77 0)
			(effects
				(font
					(size 1.27 1.27)
					(thickness 0.15)
				)
				(justify left bottom)
				(hide yes)
			)
		)
		(pin "AA10"
		)
		(pin "AA11"
		)
		(pin "AA13"
		)
		(pin "AA14"
		)
		(pin "AA15"
		)
		(pin "AA16"
		)
		(pin "AA17"
		)
		(pin "AA9"
		)
		(pin "AB10"
		)
		(pin "AB11"
		)
		(pin "AB12"
		)
		(pin "AB13"
		)
		(pin "AB14"
		)
		(pin "AB15"
		)
		(pin "AB16"
		)
		(pin "AB17"
		)
		(pin "T14"
		)
		(pin "T15"
		)
		(pin "T16"
		)
		(pin "U15"
		)
		(pin "U16"
		)
		(pin "V10"
		)
		(pin "V13"
		)
		(pin "V14"
		)
		(pin "V15"
		)
		(pin "V16"
		)
		(pin "W10"
		)
		(pin "W11"
		)
		(pin "W12"
		)
		(pin "W13"
		)
		(pin "W14"
		)
		(pin "W15"
		)
		(pin "W16"
		)
		(pin "Y10"
		)
		(pin "Y11"
		)
		(pin "Y12"
		)
		(pin "Y13"
		)
		(pin "Y14"
		)
		(pin "Y16"
		)
		(pin "Y17"
		)
		(pin "AA18"
		)
		(pin "AA19"
		)
		(pin "AA20"
		)
		(pin "AA21"
		)
		(pin "AB18"
		)
		(pin "AB20"
		)
		(pin "AB21"
		)
		(pin "AB22"
		)
		(pin "M14"
		)
		(pin "N13"
		)
		(pin "N14"
		)
		(pin "N15"
		)
		(pin "N17"
		)
		(pin "P14"
		)
		(pin "P15"
		)
		(pin "P16"
		)
		(pin "P17"
		)
		(pin "P18"
		)
		(pin "P19"
		)
		(pin "P20"
		)
		(pin "P21"
		)
		(pin "P22"
		)
		(pin "R14"
		)
		(pin "R15"
		)
		(pin "R16"
		)
		(pin "R17"
		)
		(pin "R18"
		)
		(pin "R19"
		)
		(pin "R21"
		)
		(pin "R22"
		)
		(pin "T18"
		)
		(pin "T19"
		)
		(pin "T20"
		)
		(pin "T21"
		)
		(pin "T22"
		)
		(pin "U17"
		)
		(pin "U18"
		)
		(pin "U19"
		)
		(pin "U20"
		)
		(pin "U21"
		)
		(pin "U22"
		)
		(pin "V17"
		)
		(pin "V18"
		)
		(pin "V19"
		)
		(pin "V20"
		)
		(pin "V22"
		)
		(pin "W17"
		)
		(pin "W19"
		)
		(pin "W20"
		)
		(pin "W21"
		)
		(pin "W22"
		)
		(pin "Y18"
		)
		(pin "Y19"
		)
		(pin "Y20"
		)
		(pin "Y21"
		)
		(pin "Y22"
		)
		(pin "G13"
		)
		(pin "G15"
		)
		(pin "G16"
		)
		(pin "G17"
		)
		(pin "G18"
		)
		(pin "G19"
		)
		(pin "G20"
		)
		(pin "H13"
		)
		(pin "H14"
		)
		(pin "H15"
		)
		(pin "H16"
		)
		(pin "H17"
		)
		(pin "H18"
		)
		(pin "H19"
		)
		(pin "H20"
		)
		(pin "H22"
		)
		(pin "J13"
		)
		(pin "J14"
		)
		(pin "J15"
		)
		(pin "J16"
		)
		(pin "J17"
		)
		(pin "J19"
		)
		(pin "J20"
		)
		(pin "J21"
		)
		(pin "J22"
		)
		(pin "K13"
		)
		(pin "K14"
		)
		(pin "K16"
		)
		(pin "K17"
		)
		(pin "K18"
		)
		(pin "K19"
		)
		(pin "K20"
		)
		(pin "K21"
		)
		(pin "K22"
		)
		(pin "L13"
		)
		(pin "L14"
		)
		(pin "L15"
		)
		(pin "L16"
		)
		(pin "L17"
		)
		(pin "L18"
		)
		(pin "L19"
		)
		(pin "L20"
		)
		(pin "L21"
		)
		(pin "M13"
		)
		(pin "M15"
		)
		(pin "M16"
		)
		(pin "M17"
		)
		(pin "M18"
		)
		(pin "M20"
		)
		(pin "M21"
		)
		(pin "M22"
		)
		(pin "N18"
		)
		(pin "N19"
		)
		(pin "N20"
		)
		(pin "N21"
		)
		(pin "N22"
		)
		(pin "A13"
		)
		(pin "A14"
		)
		(pin "A15"
		)
		(pin "A16"
		)
		(pin "A17"
		)
		(pin "A18"
		)
		(pin "A19"
		)
		(pin "A20"
		)
		(pin "A21"
		)
		(pin "B13"
		)
		(pin "B14"
		)
		(pin "B15"
		)
		(pin "B16"
		)
		(pin "B17"
		)
		(pin "B18"
		)
		(pin "B20"
		)
		(pin "B21"
		)
		(pin "B22"
		)
		(pin "C13"
		)
		(pin "C14"
		)
		(pin "C15"
		)
		(pin "C17"
		)
		(pin "C18"
		)
		(pin "C19"
		)
		(pin "C20"
		)
		(pin "C21"
		)
		(pin "C22"
		)
		(pin "D14"
		)
		(pin "D15"
		)
		(pin "D16"
		)
		(pin "D17"
		)
		(pin "D18"
		)
		(pin "D19"
		)
		(pin "D20"
		)
		(pin "D21"
		)
		(pin "D22"
		)
		(pin "E13"
		)
		(pin "E14"
		)
		(pin "E15"
		)
		(pin "E16"
		)
		(pin "E17"
		)
		(pin "E18"
		)
		(pin "E19"
		)
		(pin "E21"
		)
		(pin "E22"
		)
		(pin "F13"
		)
		(pin "F14"
		)
		(pin "F15"
		)
		(pin "F16"
		)
		(pin "F18"
		)
		(pin "F19"
		)
		(pin "F20"
		)
		(pin "F21"
		)
		(pin "F22"
		)
		(pin "G21"
		)
		(pin "G22"
		)
		(pin "AA1"
		)
		(pin "AA3"
		)
		(pin "AA4"
		)
		(pin "AA5"
		)
		(pin "AA6"
		)
		(pin "AA7"
		)
		(pin "AA8"
		)
		(pin "AB1"
		)
		(pin "AB2"
		)
		(pin "AB3"
		)
		(pin "AB4"
		)
		(pin "AB5"
		)
		(pin "AB6"
		)
		(pin "AB7"
		)
		(pin "AB8"
		)
		(pin "R2"
		)
		(pin "R3"
		)
		(pin "R4"
		)
		(pin "R5"
		)
		(pin "R6"
		)
		(pin "T1"
		)
		(pin "T2"
		)
		(pin "T3"
		)
		(pin "T4"
		)
		(pin "T5"
		)
		(pin "T6"
		)
		(pin "U1"
		)
		(pin "U2"
		)
		(pin "U3"
		)
		(pin "U5"
		)
		(pin "U6"
		)
		(pin "U7"
		)
		(pin "V2"
		)
		(pin "V3"
		)
		(pin "V4"
		)
		(pin "V5"
		)
		(pin "V6"
		)
		(pin "V7"
		)
		(pin "V8"
		)
		(pin "V9"
		)
		(pin "W1"
		)
		(pin "W2"
		)
		(pin "W3"
		)
		(pin "W4"
		)
		(pin "W5"
		)
		(pin "W6"
		)
		(pin "W7"
		)
		(pin "W9"
		)
		(pin "Y1"
		)
		(pin "Y2"
		)
		(pin "Y3"
		)
		(pin "Y4"
		)
		(pin "Y6"
		)
		(pin "Y7"
		)
		(pin "Y8"
		)
		(pin "Y9"
		)
		(pin "A1"
		)
		(pin "B1"
		)
		(pin "B2"
		)
		(pin "C1"
		)
		(pin "C2"
		)
		(pin "D1"
		)
		(pin "D2"
		)
		(pin "E1"
		)
		(pin "E2"
		)
		(pin "E3"
		)
		(pin "F1"
		)
		(pin "F2"
		)
		(pin "F3"
		)
		(pin "F4"
		)
		(pin "G1"
		)
		(pin "G2"
		)
		(pin "G3"
		)
		(pin "G4"
		)
		(pin "H2"
		)
		(pin "H3"
		)
		(pin "H4"
		)
		(pin "H5"
		)
		(pin "H6"
		)
		(pin "J1"
		)
		(pin "J2"
		)
		(pin "J3"
		)
		(pin "J4"
		)
		(pin "J5"
		)
		(pin "J6"
		)
		(pin "K1"
		)
		(pin "K2"
		)
		(pin "K3"
		)
		(pin "K4"
		)
		(pin "K6"
		)
		(pin "L1"
		)
		(pin "L3"
		)
		(pin "L4"
		)
		(pin "L5"
		)
		(pin "L6"
		)
		(pin "M1"
		)
		(pin "M2"
		)
		(pin "M3"
		)
		(pin "M4"
		)
		(pin "M5"
		)
		(pin "M6"
		)
		(pin "N1"
		)
		(pin "N2"
		)
		(pin "N3"
		)
		(pin "N4"
		)
		(pin "N5"
		)
		(pin "P1"
		)
		(pin "P2"
		)
		(pin "P4"
		)
		(pin "P5"
		)
		(pin "P6"
		)
		(pin "R1"
		)
		(pin "F12"
		)
		(pin "G11"
		)
		(pin "L10"
		)
		(pin "L12"
		)
		(pin "L9"
		)
		(pin "M10"
		)
		(pin "M9"
		)
		(pin "N10"
		)
		(pin "N12"
		)
		(pin "N9"
		)
		(pin "R13"
		)
		(pin "T12"
		)
		(pin "T13"
		)
		(pin "U10"
		)
		(pin "U11"
		)
		(pin "U12"
		)
		(pin "U13"
		)
		(pin "U8"
		)
		(pin "U9"
		)
		(pin "V12"
		)
		(pin "A10"
		)
		(pin "A4"
		)
		(pin "A6"
		)
		(pin "A8"
		)
		(pin "B10"
		)
		(pin "B11"
		)
		(pin "B4"
		)
		(pin "B5"
		)
		(pin "B6"
		)
		(pin "B7"
		)
		(pin "B8"
		)
		(pin "B9"
		)
		(pin "C11"
		)
		(pin "C4"
		)
		(pin "C5"
		)
		(pin "C7"
		)
		(pin "C8"
		)
		(pin "C9"
		)
		(pin "D10"
		)
		(pin "D11"
		)
		(pin "D5"
		)
		(pin "D6"
		)
		(pin "D7"
		)
		(pin "D9"
		)
		(pin "E10"
		)
		(pin "E6"
		)
		(pin "E8"
		)
		(pin "F10"
		)
		(pin "F6"
		)
		(pin "F7"
		)
		(pin "F8"
		)
		(pin "F9"
		)
		(pin "A11"
		)
		(pin "A12"
		)
		(pin "A2"
		)
		(pin "A22"
		)
		(pin "A3"
		)
		(pin "A5"
		)
		(pin "A7"
		)
		(pin "A9"
		)
		(pin "AA12"
		)
		(pin "AA2"
		)
		(pin "AA22"
		)
		(pin "AB19"
		)
		(pin "AB9"
		)
		(pin "B12"
		)
		(pin "B19"
		)
		(pin "B3"
		)
		(pin "C10"
		)
		(pin "C12"
		)
		(pin "C16"
		)
		(pin "C3"
		)
		(pin "C6"
		)
		(pin "D12"
		)
		(pin "D13"
		)
		(pin "D3"
		)
		(pin "D4"
		)
		(pin "D8"
		)
		(pin "E11"
		)
		(pin "E12"
		)
		(pin "E20"
		)
		(pin "E4"
		)
		(pin "E5"
		)
		(pin "E7"
		)
		(pin "E9"
		)
		(pin "F11"
		)
		(pin "F17"
		)
		(pin "F5"
		)
		(pin "G10"
		)
		(pin "G12"
		)
		(pin "G14"
		)
		(pin "G5"
		)
		(pin "G6"
		)
		(pin "G7"
		)
		(pin "G8"
		)
		(pin "G9"
		)
		(pin "H1"
		)
		(pin "H10"
		)
		(pin "H11"
		)
		(pin "H12"
		)
		(pin "H21"
		)
		(pin "H7"
		)
		(pin "H8"
		)
		(pin "H9"
		)
		(pin "J10"
		)
		(pin "J11"
		)
		(pin "J12"
		)
		(pin "J18"
		)
		(pin "J7"
		)
		(pin "J8"
		)
		(pin "J9"
		)
		(pin "K10"
		)
		(pin "K11"
		)
		(pin "K12"
		)
		(pin "K15"
		)
		(pin "K5"
		)
		(pin "K7"
		)
		(pin "K8"
		)
		(pin "K9"
		)
		(pin "L11"
		)
		(pin "L2"
		)
		(pin "L22"
		)
		(pin "L7"
		)
		(pin "L8"
		)
		(pin "M11"
		)
		(pin "M12"
		)
		(pin "M19"
		)
		(pin "M7"
		)
		(pin "M8"
		)
		(pin "N11"
		)
		(pin "N16"
		)
		(pin "N6"
		)
		(pin "N7"
		)
		(pin "N8"
		)
		(pin "P10"
		)
		(pin "P11"
		)
		(pin "P12"
		)
		(pin "P13"
		)
		(pin "P3"
		)
		(pin "P7"
		)
		(pin "P8"
		)
		(pin "P9"
		)
		(pin "R10"
		)
		(pin "R11"
		)
		(pin "R12"
		)
		(pin "R20"
		)
		(pin "R7"
		)
		(pin "R8"
		)
		(pin "R9"
		)
		(pin "T10"
		)
		(pin "T11"
		)
		(pin "T17"
		)
		(pin "T7"
		)
		(pin "T8"
		)
		(pin "T9"
		)
		(pin "U14"
		)
		(pin "U4"
		)
		(pin "V1"
		)
		(pin "V11"
		)
		(pin "V21"
		)
		(pin "W18"
		)
		(pin "W8"
		)
		(pin "Y15"
		)
		(pin "Y5"
		)
		(instances
			(project "artix-dc-scm"
				(path ""
					(reference "U14")
					(unit 5)
				)
			)
		)
	)
	(symbol
		(lib_id "antmicroCapacitors0402:C_100n_0402")
		(at 177.8 165.1 90)
		(unit 1)
		(exclude_from_sim no)
		(in_bom yes)
		(on_board yes)
		(dnp no)
		(property "Reference" "C253"
			(at 178.435 160.655 90)
			(effects
				(font
					(size 1.27 1.27)
				)
				(justify right)
			)
		)
		(property "Value" "C_100n_0402"
			(at 187.96 144.78 0)
			(effects
				(font
					(size 1.27 1.27)
					(thickness 0.15)
				)
				(justify left bottom)
				(hide yes)
			)
		)
		(property "Footprint" "antmicro-footprints:C_0402_1005Metric"
			(at 190.5 144.78 0)
			(effects
				(font
					(size 1.27 1.27)
					(thickness 0.15)
				)
				(justify left bottom)
				(hide yes)
			)
		)
		(property "Datasheet" "https://www.murata.com/products/productdetail?partno=GRM155R61H104KE14%23"
			(at 193.04 144.78 0)
			(effects
				(font
					(size 1.27 1.27)
					(thickness 0.15)
				)
				(justify left bottom)
				(hide yes)
			)
		)
		(property "Description" "SMD Multilayer Ceramic Capacitor, 0.1 µF, 50 V, 0402 [1005 Metric], ± 10%, X5R, GRM Series"
			(at 177.8 165.1 0)
			(effects
				(font
					(size 1.27 1.27)
				)
				(hide yes)
			)
		)
		(property "Manufacturer" "Murata"
			(at 198.12 144.78 0)
			(effects
				(font
					(size 1.27 1.27)
					(thickness 0.15)
				)
				(justify left bottom)
				(hide yes)
			)
		)
		(property "MPN" "GRM155R61H104KE14D"
			(at 195.58 144.78 0)
			(effects
				(font
					(size 1.27 1.27)
					(thickness 0.15)
				)
				(justify left bottom)
				(hide yes)
			)
		)
		(property "Val" "100n"
			(at 178.435 164.465 90)
			(effects
				(font
					(size 1.27 1.27)
					(thickness 0.15)
				)
				(justify right)
			)
		)
		(property "License" "Apache-2.0"
			(at 200.66 144.78 0)
			(effects
				(font
					(size 1.27 1.27)
					(thickness 0.15)
				)
				(justify left bottom)
				(hide yes)
			)
		)
		(property "Author" "Antmicro"
			(at 203.2 144.78 0)
			(effects
				(font
					(size 1.27 1.27)
					(thickness 0.15)
				)
				(justify left bottom)
				(hide yes)
			)
		)
		(property "Voltage" "50V"
			(at 205.74 144.78 0)
			(effects
				(font
					(size 1.27 1.27)
				)
				(justify left bottom)
				(hide yes)
			)
		)
		(property "Dielectric" "X5R"
			(at 208.28 144.78 0)
			(effects
				(font
					(size 1.27 1.27)
				)
				(justify left bottom)
				(hide yes)
			)
		)
		(pin "1"
		)
		(pin "2"
		)
		(instances
			(project "artix-dc-scm"
				(path ""
					(reference "C253")
					(unit 1)
				)
			)
		)
	)
	(symbol
		(lib_id "antmicropower:GND")
		(at 177.8 165.1 0)
		(unit 1)
		(exclude_from_sim no)
		(in_bom yes)
		(on_board yes)
		(dnp no)
		(property "Reference" "#PWR0163"
			(at 177.8 171.45 0)
			(effects
				(font
					(size 1.27 1.27)
				)
				(hide yes)
			)
		)
		(property "Value" "GND"
			(at 177.8 168.91 0)
			(effects
				(font
					(size 1.27 1.27)
				)
			)
		)
		(property "Footprint" ""
			(at 177.8 165.1 0)
			(effects
				(font
					(size 1.27 1.27)
				)
				(hide yes)
			)
		)
		(property "Datasheet" ""
			(at 177.8 165.1 0)
			(effects
				(font
					(size 1.27 1.27)
				)
				(hide yes)
			)
		)
		(property "Description" ""
			(at 177.8 165.1 0)
			(effects
				(font
					(size 1.27 1.27)
				)
				(hide yes)
			)
		)
		(property "Author" "Antmicro"
			(at 186.69 172.72 0)
			(effects
				(font
					(size 1.27 1.27)
					(thickness 0.15)
				)
				(justify left bottom)
				(hide yes)
			)
		)
		(property "License" "Apache-2.0"
			(at 186.69 175.26 0)
			(effects
				(font
					(size 1.27 1.27)
					(thickness 0.15)
				)
				(justify left bottom)
				(hide yes)
			)
		)
		(pin "1"
		)
		(instances
			(project "artix-dc-scm"
				(path ""
					(reference "#PWR0163")
					(unit 1)
				)
			)
		)
	)
	(symbol
		(lib_id "antmicroLogicTranslatorsLevelShifters:LSF0108RKSR")
		(at 187.96 167.64 0)
		(unit 1)
		(exclude_from_sim no)
		(in_bom no)
		(on_board yes)
		(dnp yes)
		(property "Reference" "U21"
			(at 197.485 160.02 0)
			(effects
				(font
					(size 1.27 1.27)
				)
			)
		)
		(property "Value" "LSF0108RKSR"
			(at 197.485 162.56 0)
			(effects
				(font
					(size 1.27 1.27)
				)
			)
		)
		(property "Footprint" "antmicro-footprints:VQFN-20_1EP_4.5x2.5mm_P0.5mm"
			(at 195.58 190.5 0)
			(effects
				(font
					(size 1.27 1.27)
				)
				(justify left bottom)
				(hide yes)
			)
		)
		(property "Datasheet" "https://www.ti.com/lit/ds/symlink/lsf0108.pdf?ts=1686550470995&ref_url=https%253A%252F%252Fwww.ti.com%252Fproduct%252FLSF0108%252Fpart-details%252FLSF0108RKSR"
			(at 187.96 167.64 0)
			(effects
				(font
					(size 1.27 1.27)
				)
				(justify left bottom)
				(hide yes)
			)
		)
		(property "Description" "Voltage Level Translator, 8 Input, 1.5 ns, 0 V to 5 V, VQFN-20"
			(at 187.96 167.64 0)
			(effects
				(font
					(size 1.27 1.27)
				)
				(hide yes)
			)
		)
		(property "Manufacturer" "Texas Instruments"
			(at 195.58 191.77 0)
			(effects
				(font
					(size 1.27 1.27)
				)
				(justify left bottom)
				(hide yes)
			)
		)
		(property "MPN" "LSF0108RKSR"
			(at 187.96 167.64 0)
			(effects
				(font
					(size 1.27 1.27)
				)
				(hide yes)
			)
		)
		(property "Author" "Antmicro"
			(at 220.98 185.42 0)
			(effects
				(font
					(size 1.27 1.27)
					(thickness 0.15)
				)
				(justify left bottom)
				(hide yes)
			)
		)
		(property "License" "Apache-2.0"
			(at 220.98 187.96 0)
			(effects
				(font
					(size 1.27 1.27)
					(thickness 0.15)
				)
				(justify left bottom)
				(hide yes)
			)
		)
		(pin "1"
		)
		(pin "10"
		)
		(pin "11"
		)
		(pin "12"
		)
		(pin "13"
		)
		(pin "14"
		)
		(pin "15"
		)
		(pin "16"
		)
		(pin "17"
		)
		(pin "18"
		)
		(pin "19"
		)
		(pin "2"
		)
		(pin "20"
		)
		(pin "21"
		)
		(pin "3"
		)
		(pin "4"
		)
		(pin "5"
		)
		(pin "6"
		)
		(pin "7"
		)
		(pin "8"
		)
		(pin "9"
		)
		(instances
			(project "artix-dc-scm"
				(path ""
					(reference "U21")
					(unit 1)
				)
			)
		)
	)
	(symbol
		(lib_id "antmicroLogicTranslatorsLevelShifters:LSF0101DRYR")
		(at 187.96 217.17 0)
		(unit 1)
		(exclude_from_sim no)
		(in_bom yes)
		(on_board yes)
		(dnp no)
		(fields_autoplaced yes)
		(property "Reference" "U22"
			(at 197.485 209.55 0)
			(effects
				(font
					(size 1.27 1.27)
				)
			)
		)
		(property "Value" "LSF0101DRYR"
			(at 197.485 212.09 0)
			(effects
				(font
					(size 1.27 1.27)
				)
			)
		)
		(property "Footprint" "antmicro-footprints:USON-6_1.45x1.0mm_P0.5mm_Texas_DRY6"
			(at 175.26 229.87 0)
			(effects
				(font
					(size 1.27 1.27)
				)
				(justify left bottom)
				(hide yes)
			)
		)
		(property "Datasheet" "https://www.ti.com/lit/ds/symlink/lsf0101.pdf?ts=1686656250822&ref_url=https%253A%252F%252Fwww.ti.com%252Fproduct%252FLSF0101%252Fpart-details%252FLSF0101DRYR"
			(at 187.96 217.17 0)
			(effects
				(font
					(size 1.27 1.27)
				)
				(justify left bottom)
				(hide yes)
			)
		)
		(property "Description" "Voltage Level Translator, 1 Input, 1.5 ns, 0 V to 5 V, SON-6"
			(at 187.96 217.17 0)
			(effects
				(font
					(size 1.27 1.27)
				)
				(hide yes)
			)
		)
		(property "MPN" "LSF0101DRYR"
			(at 187.96 217.17 0)
			(effects
				(font
					(size 1.27 1.27)
				)
				(hide yes)
			)
		)
		(property "Manufacturer" "Texas Instruments"
			(at 187.96 217.17 0)
			(effects
				(font
					(size 1.27 1.27)
				)
				(hide yes)
			)
		)
		(property "Author" "Antmicro"
			(at 220.98 234.95 0)
			(effects
				(font
					(size 1.27 1.27)
					(thickness 0.15)
				)
				(justify left bottom)
				(hide yes)
			)
		)
		(property "License" "Apache-2.0"
			(at 220.98 237.49 0)
			(effects
				(font
					(size 1.27 1.27)
					(thickness 0.15)
				)
				(justify left bottom)
				(hide yes)
			)
		)
		(pin "1"
		)
		(pin "2"
		)
		(pin "3"
		)
		(pin "4"
		)
		(pin "5"
		)
		(pin "6"
		)
		(instances
			(project "artix-dc-scm"
				(path ""
					(reference "U22")
					(unit 1)
				)
			)
		)
	)
	(symbol
		(lib_id "antmicropower:GND")
		(at 341.63 44.45 0)
		(unit 1)
		(exclude_from_sim no)
		(in_bom yes)
		(on_board yes)
		(dnp no)
		(property "Reference" "#PWR0112"
			(at 341.63 50.8 0)
			(effects
				(font
					(size 1.27 1.27)
				)
				(hide yes)
			)
		)
		(property "Value" "GND"
			(at 341.63 48.26 0)
			(effects
				(font
					(size 1.27 1.27)
				)
			)
		)
		(property "Footprint" ""
			(at 341.63 44.45 0)
			(effects
				(font
					(size 1.27 1.27)
				)
				(hide yes)
			)
		)
		(property "Datasheet" ""
			(at 341.63 44.45 0)
			(effects
				(font
					(size 1.27 1.27)
				)
				(hide yes)
			)
		)
		(property "Description" ""
			(at 341.63 44.45 0)
			(effects
				(font
					(size 1.27 1.27)
				)
				(hide yes)
			)
		)
		(property "Author" "Antmicro"
			(at 350.52 52.07 0)
			(effects
				(font
					(size 1.27 1.27)
					(thickness 0.15)
				)
				(justify left bottom)
				(hide yes)
			)
		)
		(property "License" "Apache-2.0"
			(at 350.52 54.61 0)
			(effects
				(font
					(size 1.27 1.27)
					(thickness 0.15)
				)
				(justify left bottom)
				(hide yes)
			)
		)
		(pin "1"
		)
		(instances
			(project "artix-dc-scm"
				(path ""
					(reference "#PWR0112")
					(unit 1)
				)
			)
		)
	)
	(symbol
		(lib_id "antmicroCapacitors0402:C_100n_0402")
		(at 393.7 44.45 90)
		(unit 1)
		(exclude_from_sim no)
		(in_bom yes)
		(on_board yes)
		(dnp no)
		(property "Reference" "C25"
			(at 394.335 40.005 90)
			(effects
				(font
					(size 1.27 1.27)
				)
				(justify right)
			)
		)
		(property "Value" "C_100n_0402"
			(at 403.86 24.13 0)
			(effects
				(font
					(size 1.27 1.27)
					(thickness 0.15)
				)
				(justify left bottom)
				(hide yes)
			)
		)
		(property "Footprint" "antmicro-footprints:C_0402_1005Metric"
			(at 406.4 24.13 0)
			(effects
				(font
					(size 1.27 1.27)
					(thickness 0.15)
				)
				(justify left bottom)
				(hide yes)
			)
		)
		(property "Datasheet" "https://www.murata.com/products/productdetail?partno=GRM155R61H104KE14%23"
			(at 408.94 24.13 0)
			(effects
				(font
					(size 1.27 1.27)
					(thickness 0.15)
				)
				(justify left bottom)
				(hide yes)
			)
		)
		(property "Description" "SMD Multilayer Ceramic Capacitor, 0.1 µF, 50 V, 0402 [1005 Metric], ± 10%, X5R, GRM Series"
			(at 393.7 44.45 0)
			(effects
				(font
					(size 1.27 1.27)
				)
				(hide yes)
			)
		)
		(property "Manufacturer" "Murata"
			(at 414.02 24.13 0)
			(effects
				(font
					(size 1.27 1.27)
					(thickness 0.15)
				)
				(justify left bottom)
				(hide yes)
			)
		)
		(property "MPN" "GRM155R61H104KE14D"
			(at 411.48 24.13 0)
			(effects
				(font
					(size 1.27 1.27)
					(thickness 0.15)
				)
				(justify left bottom)
				(hide yes)
			)
		)
		(property "Val" "100n"
			(at 394.335 43.815 90)
			(effects
				(font
					(size 1.27 1.27)
					(thickness 0.15)
				)
				(justify right)
			)
		)
		(property "License" "Apache-2.0"
			(at 416.56 24.13 0)
			(effects
				(font
					(size 1.27 1.27)
					(thickness 0.15)
				)
				(justify left bottom)
				(hide yes)
			)
		)
		(property "Author" "Antmicro"
			(at 419.1 24.13 0)
			(effects
				(font
					(size 1.27 1.27)
					(thickness 0.15)
				)
				(justify left bottom)
				(hide yes)
			)
		)
		(property "Voltage" "50V"
			(at 421.64 24.13 0)
			(effects
				(font
					(size 1.27 1.27)
				)
				(justify left bottom)
				(hide yes)
			)
		)
		(property "Dielectric" "X5R"
			(at 424.18 24.13 0)
			(effects
				(font
					(size 1.27 1.27)
				)
				(justify left bottom)
				(hide yes)
			)
		)
		(pin "1"
		)
		(pin "2"
		)
		(instances
			(project "artix-dc-scm"
				(path ""
					(reference "C25")
					(unit 1)
				)
			)
		)
	)
	(symbol
		(lib_id "antmicropower:GND")
		(at 208.28 199.39 0)
		(unit 1)
		(exclude_from_sim no)
		(in_bom yes)
		(on_board yes)
		(dnp no)
		(property "Reference" "#PWR0161"
			(at 208.28 205.74 0)
			(effects
				(font
					(size 1.27 1.27)
				)
				(hide yes)
			)
		)
		(property "Value" "GND"
			(at 208.28 203.2 0)
			(effects
				(font
					(size 1.27 1.27)
				)
			)
		)
		(property "Footprint" ""
			(at 208.28 199.39 0)
			(effects
				(font
					(size 1.27 1.27)
				)
				(hide yes)
			)
		)
		(property "Datasheet" ""
			(at 208.28 199.39 0)
			(effects
				(font
					(size 1.27 1.27)
				)
				(hide yes)
			)
		)
		(property "Description" ""
			(at 208.28 199.39 0)
			(effects
				(font
					(size 1.27 1.27)
				)
				(hide yes)
			)
		)
		(property "Author" "Antmicro"
			(at 217.17 207.01 0)
			(effects
				(font
					(size 1.27 1.27)
					(thickness 0.15)
				)
				(justify left bottom)
				(hide yes)
			)
		)
		(property "License" "Apache-2.0"
			(at 217.17 209.55 0)
			(effects
				(font
					(size 1.27 1.27)
					(thickness 0.15)
				)
				(justify left bottom)
				(hide yes)
			)
		)
		(pin "1"
		)
		(instances
			(project "artix-dc-scm"
				(path ""
					(reference "#PWR0161")
					(unit 1)
				)
			)
		)
	)
	(symbol
		(lib_id "antmicropower:GND")
		(at 208.28 228.6 0)
		(unit 1)
		(exclude_from_sim no)
		(in_bom yes)
		(on_board yes)
		(dnp no)
		(property "Reference" "#PWR0160"
			(at 208.28 234.95 0)
			(effects
				(font
					(size 1.27 1.27)
				)
				(hide yes)
			)
		)
		(property "Value" "GND"
			(at 208.28 232.41 0)
			(effects
				(font
					(size 1.27 1.27)
				)
			)
		)
		(property "Footprint" ""
			(at 208.28 228.6 0)
			(effects
				(font
					(size 1.27 1.27)
				)
				(hide yes)
			)
		)
		(property "Datasheet" ""
			(at 208.28 228.6 0)
			(effects
				(font
					(size 1.27 1.27)
				)
				(hide yes)
			)
		)
		(property "Description" ""
			(at 208.28 228.6 0)
			(effects
				(font
					(size 1.27 1.27)
				)
				(hide yes)
			)
		)
		(property "Author" "Antmicro"
			(at 217.17 236.22 0)
			(effects
				(font
					(size 1.27 1.27)
					(thickness 0.15)
				)
				(justify left bottom)
				(hide yes)
			)
		)
		(property "License" "Apache-2.0"
			(at 217.17 238.76 0)
			(effects
				(font
					(size 1.27 1.27)
					(thickness 0.15)
				)
				(justify left bottom)
				(hide yes)
			)
		)
		(pin "1"
		)
		(instances
			(project "artix-dc-scm"
				(path ""
					(reference "#PWR0160")
					(unit 1)
				)
			)
		)
	)
	(symbol
		(lib_id "antmicroTVSDiodes:SP3011-06UTG")
		(at 241.3 66.04 90)
		(mirror x)
		(unit 1)
		(exclude_from_sim no)
		(in_bom yes)
		(on_board yes)
		(dnp no)
		(property "Reference" "D2"
			(at 240.03 76.835 90)
			(effects
				(font
					(size 1.27 1.27)
				)
			)
		)
		(property "Value" "SP3011-06UTG"
			(at 252.73 76.835 90)
			(effects
				(font
					(size 1.27 1.27)
					(thickness 0.15)
				)
			)
		)
		(property "Footprint" "antmicro-footprints:USON-14_3.5x1.35_P0.5mm"
			(at 250.19 80.01 0)
			(effects
				(font
					(size 1.27 1.27)
					(thickness 0.15)
				)
				(justify left bottom)
				(hide yes)
			)
		)
		(property "Datasheet" "https://www.littelfuse.com/media?resourcetype=datasheets&itemid=c9002a97-9994-449b-b722-f45ab5538c7f&filename=littelfuse-tvs-diode-array-sp3011-datasheet"
			(at 252.73 80.01 0)
			(effects
				(font
					(size 1.27 1.27)
					(thickness 0.15)
				)
				(justify left bottom)
				(hide yes)
			)
		)
		(property "Description" "TVS diode array, 8 kV, USON-14, 6 V, 0.4 pF"
			(at 241.3 66.04 0)
			(effects
				(font
					(size 1.27 1.27)
				)
				(hide yes)
			)
		)
		(property "MPN" "SP3011-06UTG"
			(at 255.27 80.01 0)
			(effects
				(font
					(size 1.27 1.27)
					(thickness 0.15)
				)
				(justify left bottom)
				(hide yes)
			)
		)
		(property "Manufacturer" "Littelfuse"
			(at 257.81 80.01 0)
			(effects
				(font
					(size 1.27 1.27)
					(thickness 0.15)
				)
				(justify left bottom)
				(hide yes)
			)
		)
		(property "Author" "Antmicro"
			(at 260.35 80.01 0)
			(effects
				(font
					(size 1.27 1.27)
					(thickness 0.15)
				)
				(justify left bottom)
				(hide yes)
			)
		)
		(property "License" "Apache-2.0"
			(at 262.89 80.01 0)
			(effects
				(font
					(size 1.27 1.27)
					(thickness 0.15)
				)
				(justify left bottom)
				(hide yes)
			)
		)
		(pin "11"
		)
		(pin "12"
		)
		(pin "13"
		)
		(pin "14"
		)
		(pin "1"
		)
		(pin "10"
		)
		(pin "2"
		)
		(pin "3"
		)
		(pin "4"
		)
		(pin "5"
		)
		(pin "6"
		)
		(pin "7"
		)
		(pin "8"
		)
		(pin "9"
		)
		(instances
			(project "artix-dc-scm"
				(path ""
					(reference "D2")
					(unit 1)
				)
			)
		)
	)
	(symbol
		(lib_id "antmicroResistors0402:R_200k_0402")
		(at 223.52 165.1 270)
		(mirror x)
		(unit 1)
		(exclude_from_sim no)
		(in_bom yes)
		(on_board yes)
		(dnp no)
		(property "Reference" "R12"
			(at 224.79 161.29 90)
			(effects
				(font
					(size 1.27 1.27)
				)
				(justify left)
			)
		)
		(property "Value" "R_200k_0402"
			(at 219.71 165.1 0)
			(effects
				(font
					(size 1.27 1.27)
				)
				(hide yes)
			)
		)
		(property "Footprint" "antmicro-footprints:R_0402_1005Metric"
			(at 208.28 144.78 0)
			(effects
				(font
					(size 1.27 1.27)
					(thickness 0.15)
				)
				(justify left bottom)
				(hide yes)
			)
		)
		(property "Datasheet" "https://www.bourns.com/docs/product-datasheets/cr.pdf"
			(at 205.74 144.78 0)
			(effects
				(font
					(size 1.27 1.27)
					(thickness 0.15)
				)
				(justify left bottom)
				(hide yes)
			)
		)
		(property "Description" "SMD Chip Resistor, 200 kohm, ± 1%, 62.5 mW, 0402 [1005 Metric], Thick Film, General Purpose"
			(at 223.52 165.1 0)
			(effects
				(font
					(size 1.27 1.27)
				)
				(hide yes)
			)
		)
		(property "Manufacturer" "Bourns"
			(at 200.66 144.78 0)
			(effects
				(font
					(size 1.27 1.27)
					(thickness 0.15)
				)
				(justify left bottom)
				(hide yes)
			)
		)
		(property "MPN" "CR0402-FX-2003GLF"
			(at 203.2 144.78 0)
			(effects
				(font
					(size 1.27 1.27)
					(thickness 0.15)
				)
				(justify left bottom)
				(hide yes)
			)
		)
		(property "Val" "200k"
			(at 224.79 163.83 90)
			(effects
				(font
					(size 1.27 1.27)
					(thickness 0.15)
				)
				(justify left)
			)
		)
		(property "License" "Apache-2.0"
			(at 198.12 144.78 0)
			(effects
				(font
					(size 1.27 1.27)
					(thickness 0.15)
				)
				(justify left bottom)
				(hide yes)
			)
		)
		(property "Author" "Antmicro"
			(at 195.58 144.78 0)
			(effects
				(font
					(size 1.27 1.27)
					(thickness 0.15)
				)
				(justify left bottom)
				(hide yes)
			)
		)
		(property "Tolerance" "1%"
			(at 213.36 144.78 0)
			(effects
				(font
					(size 1.27 1.27)
				)
				(justify left bottom)
				(hide yes)
			)
		)
		(pin "1"
		)
		(pin "2"
		)
		(instances
			(project "artix-dc-scm"
				(path ""
					(reference "R12")
					(unit 1)
				)
			)
		)
	)
	(symbol
		(lib_id "antmicroOscillators:Oscillator_24MHz_ASEMB")
		(at 323.85 173.99 0)
		(unit 1)
		(exclude_from_sim no)
		(in_bom yes)
		(on_board yes)
		(dnp no)
		(fields_autoplaced yes)
		(property "Reference" "U23"
			(at 333.375 165.735 0)
			(effects
				(font
					(size 1.27 1.27)
				)
			)
		)
		(property "Value" "Oscillator_24MHz_ASEMB"
			(at 333.375 168.275 0)
			(effects
				(font
					(size 1.27 1.27)
				)
			)
		)
		(property "Footprint" "antmicro-footprints:Oscillator_SMD_Abracon_ASEMB_3.2x2.5mm"
			(at 355.6 182.88 0)
			(effects
				(font
					(size 1.27 1.27)
					(thickness 0.15)
				)
				(justify left bottom)
				(hide yes)
			)
		)
		(property "Datasheet" "https://abracon.com/Oscillators/ASEMB.pdf"
			(at 355.6 185.42 0)
			(effects
				(font
					(size 1.27 1.27)
					(thickness 0.15)
				)
				(justify left bottom)
				(hide yes)
			)
		)
		(property "Description" "MEMS Oscillator, Clock, Pure Silicon&trade;, 24 MHz, SMD, 3.2mm x 2.5mm, 50 ppm, 3.3 V, ASEMB, LVCMOS"
			(at 323.85 173.99 0)
			(effects
				(font
					(size 1.27 1.27)
				)
				(hide yes)
			)
		)
		(property "MPN" "ASEMB-24.000MHZ-LC-T"
			(at 355.6 187.96 0)
			(effects
				(font
					(size 1.27 1.27)
					(thickness 0.15)
				)
				(justify left bottom)
				(hide yes)
			)
		)
		(property "Manufacturer" "Abracon"
			(at 355.6 190.5 0)
			(effects
				(font
					(size 1.27 1.27)
					(thickness 0.15)
				)
				(justify left bottom)
				(hide yes)
			)
		)
		(property "Author" "Antmicro"
			(at 355.6 193.04 0)
			(effects
				(font
					(size 1.27 1.27)
					(thickness 0.15)
				)
				(justify left bottom)
				(hide yes)
			)
		)
		(property "License" "Apache-2.0"
			(at 355.6 195.58 0)
			(effects
				(font
					(size 1.27 1.27)
					(thickness 0.15)
				)
				(justify left bottom)
				(hide yes)
			)
		)
		(property "Val" "24 MHz"
			(at 355.6 198.12 0)
			(effects
				(font
					(size 1.27 1.27)
				)
				(justify left bottom)
				(hide yes)
			)
		)
		(pin "1"
		)
		(pin "2"
		)
		(pin "3"
		)
		(pin "4"
		)
		(instances
			(project "artix-dc-scm"
				(path ""
					(reference "U23")
					(unit 1)
				)
			)
		)
	)
	(symbol
		(lib_id "antmicroResistors0402:R_12k_0402")
		(at 347.98 86.36 0)
		(unit 1)
		(exclude_from_sim no)
		(in_bom yes)
		(on_board yes)
		(dnp no)
		(property "Reference" "R5"
			(at 353.06 85.09 0)
			(effects
				(font
					(size 1.27 1.27)
				)
				(justify left)
			)
		)
		(property "Value" "R_12k_0402"
			(at 368.3 99.06 0)
			(effects
				(font
					(size 1.27 1.27)
					(thickness 0.15)
				)
				(justify left bottom)
				(hide yes)
			)
		)
		(property "Footprint" "antmicro-footprints:R_0402_1005Metric"
			(at 368.3 101.6 0)
			(effects
				(font
					(size 1.27 1.27)
					(thickness 0.15)
				)
				(justify left bottom)
				(hide yes)
			)
		)
		(property "Datasheet" "https://www.bourns.com/docs/product-datasheets/cr.pdf"
			(at 368.3 104.14 0)
			(effects
				(font
					(size 1.27 1.27)
					(thickness 0.15)
				)
				(justify left bottom)
				(hide yes)
			)
		)
		(property "Description" "SMD Chip Resistor, 12 kohm, ± 1%, 62.5 mW, 0402 [1005 Metric], Thick Film, General Purpose"
			(at 347.98 86.36 0)
			(effects
				(font
					(size 1.27 1.27)
				)
				(hide yes)
			)
		)
		(property "Manufacturer" "Bourns"
			(at 368.3 109.22 0)
			(effects
				(font
					(size 1.27 1.27)
					(thickness 0.15)
				)
				(justify left bottom)
				(hide yes)
			)
		)
		(property "MPN" "CR0402-FX-1202GLF"
			(at 368.3 106.68 0)
			(effects
				(font
					(size 1.27 1.27)
					(thickness 0.15)
				)
				(justify left bottom)
				(hide yes)
			)
		)
		(property "Val" "12k"
			(at 346.71 85.09 0)
			(effects
				(font
					(size 1.27 1.27)
					(thickness 0.15)
				)
			)
		)
		(property "License" "Apache-2.0"
			(at 368.3 111.76 0)
			(effects
				(font
					(size 1.27 1.27)
					(thickness 0.15)
				)
				(justify left bottom)
				(hide yes)
			)
		)
		(property "Author" "Antmicro"
			(at 368.3 114.3 0)
			(effects
				(font
					(size 1.27 1.27)
					(thickness 0.15)
				)
				(justify left bottom)
				(hide yes)
			)
		)
		(property "Tolerance" "1%"
			(at 368.3 96.52 0)
			(effects
				(font
					(size 1.27 1.27)
				)
				(justify left bottom)
				(hide yes)
			)
		)
		(pin "1"
		)
		(pin "2"
		)
		(instances
			(project "artix-dc-scm"
				(path ""
					(reference "R5")
					(unit 1)
				)
			)
		)
	)
	(symbol
		(lib_id "antmicroResistors0402:R_0R_0402")
		(at 349.25 39.37 270)
		(unit 1)
		(exclude_from_sim no)
		(in_bom yes)
		(on_board yes)
		(dnp no)
		(property "Reference" "R10"
			(at 350.52 40.64 90)
			(effects
				(font
					(size 1.27 1.27)
				)
				(justify left)
			)
		)
		(property "Value" "R_0R_0402"
			(at 336.55 59.69 0)
			(effects
				(font
					(size 1.27 1.27)
					(thickness 0.15)
				)
				(justify left bottom)
				(hide yes)
			)
		)
		(property "Footprint" "antmicro-footprints:R_0402_1005Metric"
			(at 334.01 59.69 0)
			(effects
				(font
					(size 1.27 1.27)
					(thickness 0.15)
				)
				(justify left bottom)
				(hide yes)
			)
		)
		(property "Datasheet" "https://industrial.panasonic.com/cdbs/www-data/pdf/RDA0000/AOA0000C301.pdf"
			(at 331.47 59.69 0)
			(effects
				(font
					(size 1.27 1.27)
					(thickness 0.15)
				)
				(justify left bottom)
				(hide yes)
			)
		)
		(property "Description" "SMD Chip Resistor, Jumper, 0 ohm, 100 mW, 0402 [1005 Metric], Thick Film, General Purpose"
			(at 349.25 39.37 0)
			(effects
				(font
					(size 1.27 1.27)
				)
				(hide yes)
			)
		)
		(property "Manufacturer" "Panasonic"
			(at 326.39 59.69 0)
			(effects
				(font
					(size 1.27 1.27)
					(thickness 0.15)
				)
				(justify left bottom)
				(hide yes)
			)
		)
		(property "MPN" "ERJ2GE0R00X"
			(at 328.93 59.69 0)
			(effects
				(font
					(size 1.27 1.27)
					(thickness 0.15)
				)
				(justify left bottom)
				(hide yes)
			)
		)
		(property "Val" "0R"
			(at 350.52 43.18 90)
			(effects
				(font
					(size 1.27 1.27)
					(thickness 0.15)
				)
				(justify left)
			)
		)
		(property "License" "Apache-2.0"
			(at 323.85 59.69 0)
			(effects
				(font
					(size 1.27 1.27)
					(thickness 0.15)
				)
				(justify left bottom)
				(hide yes)
			)
		)
		(property "Author" "Antmicro"
			(at 321.31 59.69 0)
			(effects
				(font
					(size 1.27 1.27)
					(thickness 0.15)
				)
				(justify left bottom)
				(hide yes)
			)
		)
		(property "Tolerance" "~"
			(at 339.09 59.69 0)
			(effects
				(font
					(size 1.27 1.27)
				)
				(justify left bottom)
				(hide yes)
			)
		)
		(property "Current" "1A"
			(at 345.44 41.91 0)
			(effects
				(font
					(size 1.27 1.27)
					(thickness 0.15)
				)
				(hide yes)
			)
		)
		(pin "1"
		)
		(pin "2"
		)
		(instances
			(project "artix-dc-scm"
				(path ""
					(reference "R10")
					(unit 1)
				)
			)
		)
	)
	(symbol
		(lib_id "antmicroCapacitors0402:C_100n_0402")
		(at 317.5 135.89 90)
		(unit 1)
		(exclude_from_sim no)
		(in_bom yes)
		(on_board yes)
		(dnp no)
		(property "Reference" "C12"
			(at 318.135 131.445 90)
			(effects
				(font
					(size 1.27 1.27)
				)
				(justify right)
			)
		)
		(property "Value" "C_100n_0402"
			(at 327.66 115.57 0)
			(effects
				(font
					(size 1.27 1.27)
					(thickness 0.15)
				)
				(justify left bottom)
				(hide yes)
			)
		)
		(property "Footprint" "antmicro-footprints:C_0402_1005Metric"
			(at 330.2 115.57 0)
			(effects
				(font
					(size 1.27 1.27)
					(thickness 0.15)
				)
				(justify left bottom)
				(hide yes)
			)
		)
		(property "Datasheet" "https://www.murata.com/products/productdetail?partno=GRM155R61H104KE14%23"
			(at 332.74 115.57 0)
			(effects
				(font
					(size 1.27 1.27)
					(thickness 0.15)
				)
				(justify left bottom)
				(hide yes)
			)
		)
		(property "Description" "SMD Multilayer Ceramic Capacitor, 0.1 µF, 50 V, 0402 [1005 Metric], ± 10%, X5R, GRM Series"
			(at 317.5 135.89 0)
			(effects
				(font
					(size 1.27 1.27)
				)
				(hide yes)
			)
		)
		(property "Manufacturer" "Murata"
			(at 337.82 115.57 0)
			(effects
				(font
					(size 1.27 1.27)
					(thickness 0.15)
				)
				(justify left bottom)
				(hide yes)
			)
		)
		(property "MPN" "GRM155R61H104KE14D"
			(at 335.28 115.57 0)
			(effects
				(font
					(size 1.27 1.27)
					(thickness 0.15)
				)
				(justify left bottom)
				(hide yes)
			)
		)
		(property "Val" "100n"
			(at 318.135 135.255 90)
			(effects
				(font
					(size 1.27 1.27)
					(thickness 0.15)
				)
				(justify right)
			)
		)
		(property "License" "Apache-2.0"
			(at 340.36 115.57 0)
			(effects
				(font
					(size 1.27 1.27)
					(thickness 0.15)
				)
				(justify left bottom)
				(hide yes)
			)
		)
		(property "Author" "Antmicro"
			(at 342.9 115.57 0)
			(effects
				(font
					(size 1.27 1.27)
					(thickness 0.15)
				)
				(justify left bottom)
				(hide yes)
			)
		)
		(property "Voltage" "50V"
			(at 345.44 115.57 0)
			(effects
				(font
					(size 1.27 1.27)
				)
				(justify left bottom)
				(hide yes)
			)
		)
		(property "Dielectric" "X5R"
			(at 347.98 115.57 0)
			(effects
				(font
					(size 1.27 1.27)
				)
				(justify left bottom)
				(hide yes)
			)
		)
		(pin "1"
		)
		(pin "2"
		)
		(instances
			(project "artix-dc-scm"
				(path ""
					(reference "C12")
					(unit 1)
				)
			)
		)
	)
	(symbol
		(lib_id "antmicroCapacitors0402:C_100n_0402")
		(at 326.39 135.89 90)
		(unit 1)
		(exclude_from_sim no)
		(in_bom yes)
		(on_board yes)
		(dnp no)
		(property "Reference" "C18"
			(at 327.025 131.445 90)
			(effects
				(font
					(size 1.27 1.27)
				)
				(justify right)
			)
		)
		(property "Value" "C_100n_0402"
			(at 336.55 115.57 0)
			(effects
				(font
					(size 1.27 1.27)
					(thickness 0.15)
				)
				(justify left bottom)
				(hide yes)
			)
		)
		(property "Footprint" "antmicro-footprints:C_0402_1005Metric"
			(at 339.09 115.57 0)
			(effects
				(font
					(size 1.27 1.27)
					(thickness 0.15)
				)
				(justify left bottom)
				(hide yes)
			)
		)
		(property "Datasheet" "https://www.murata.com/products/productdetail?partno=GRM155R61H104KE14%23"
			(at 341.63 115.57 0)
			(effects
				(font
					(size 1.27 1.27)
					(thickness 0.15)
				)
				(justify left bottom)
				(hide yes)
			)
		)
		(property "Description" "SMD Multilayer Ceramic Capacitor, 0.1 µF, 50 V, 0402 [1005 Metric], ± 10%, X5R, GRM Series"
			(at 326.39 135.89 0)
			(effects
				(font
					(size 1.27 1.27)
				)
				(hide yes)
			)
		)
		(property "Manufacturer" "Murata"
			(at 346.71 115.57 0)
			(effects
				(font
					(size 1.27 1.27)
					(thickness 0.15)
				)
				(justify left bottom)
				(hide yes)
			)
		)
		(property "MPN" "GRM155R61H104KE14D"
			(at 344.17 115.57 0)
			(effects
				(font
					(size 1.27 1.27)
					(thickness 0.15)
				)
				(justify left bottom)
				(hide yes)
			)
		)
		(property "Val" "100n"
			(at 327.025 135.255 90)
			(effects
				(font
					(size 1.27 1.27)
					(thickness 0.15)
				)
				(justify right)
			)
		)
		(property "License" "Apache-2.0"
			(at 349.25 115.57 0)
			(effects
				(font
					(size 1.27 1.27)
					(thickness 0.15)
				)
				(justify left bottom)
				(hide yes)
			)
		)
		(property "Author" "Antmicro"
			(at 351.79 115.57 0)
			(effects
				(font
					(size 1.27 1.27)
					(thickness 0.15)
				)
				(justify left bottom)
				(hide yes)
			)
		)
		(property "Voltage" "50V"
			(at 354.33 115.57 0)
			(effects
				(font
					(size 1.27 1.27)
				)
				(justify left bottom)
				(hide yes)
			)
		)
		(property "Dielectric" "X5R"
			(at 356.87 115.57 0)
			(effects
				(font
					(size 1.27 1.27)
				)
				(justify left bottom)
				(hide yes)
			)
		)
		(pin "1"
		)
		(pin "2"
		)
		(instances
			(project "artix-dc-scm"
				(path ""
					(reference "C18")
					(unit 1)
				)
			)
		)
	)
	(symbol
		(lib_id "antmicroCapacitors0402:C_100n_0402")
		(at 334.01 135.89 90)
		(unit 1)
		(exclude_from_sim no)
		(in_bom yes)
		(on_board yes)
		(dnp no)
		(property "Reference" "C21"
			(at 334.645 131.445 90)
			(effects
				(font
					(size 1.27 1.27)
				)
				(justify right)
			)
		)
		(property "Value" "C_100n_0402"
			(at 344.17 115.57 0)
			(effects
				(font
					(size 1.27 1.27)
					(thickness 0.15)
				)
				(justify left bottom)
				(hide yes)
			)
		)
		(property "Footprint" "antmicro-footprints:C_0402_1005Metric"
			(at 346.71 115.57 0)
			(effects
				(font
					(size 1.27 1.27)
					(thickness 0.15)
				)
				(justify left bottom)
				(hide yes)
			)
		)
		(property "Datasheet" "https://www.murata.com/products/productdetail?partno=GRM155R61H104KE14%23"
			(at 349.25 115.57 0)
			(effects
				(font
					(size 1.27 1.27)
					(thickness 0.15)
				)
				(justify left bottom)
				(hide yes)
			)
		)
		(property "Description" "SMD Multilayer Ceramic Capacitor, 0.1 µF, 50 V, 0402 [1005 Metric], ± 10%, X5R, GRM Series"
			(at 334.01 135.89 0)
			(effects
				(font
					(size 1.27 1.27)
				)
				(hide yes)
			)
		)
		(property "Manufacturer" "Murata"
			(at 354.33 115.57 0)
			(effects
				(font
					(size 1.27 1.27)
					(thickness 0.15)
				)
				(justify left bottom)
				(hide yes)
			)
		)
		(property "MPN" "GRM155R61H104KE14D"
			(at 351.79 115.57 0)
			(effects
				(font
					(size 1.27 1.27)
					(thickness 0.15)
				)
				(justify left bottom)
				(hide yes)
			)
		)
		(property "Val" "100n"
			(at 334.645 135.255 90)
			(effects
				(font
					(size 1.27 1.27)
					(thickness 0.15)
				)
				(justify right)
			)
		)
		(property "License" "Apache-2.0"
			(at 356.87 115.57 0)
			(effects
				(font
					(size 1.27 1.27)
					(thickness 0.15)
				)
				(justify left bottom)
				(hide yes)
			)
		)
		(property "Author" "Antmicro"
			(at 359.41 115.57 0)
			(effects
				(font
					(size 1.27 1.27)
					(thickness 0.15)
				)
				(justify left bottom)
				(hide yes)
			)
		)
		(property "Voltage" "50V"
			(at 361.95 115.57 0)
			(effects
				(font
					(size 1.27 1.27)
				)
				(justify left bottom)
				(hide yes)
			)
		)
		(property "Dielectric" "X5R"
			(at 364.49 115.57 0)
			(effects
				(font
					(size 1.27 1.27)
				)
				(justify left bottom)
				(hide yes)
			)
		)
		(pin "1"
		)
		(pin "2"
		)
		(instances
			(project "artix-dc-scm"
				(path ""
					(reference "C21")
					(unit 1)
				)
			)
		)
	)
	(symbol
		(lib_id "antmicroCapacitors0402:C_100n_0402")
		(at 341.63 135.89 90)
		(unit 1)
		(exclude_from_sim no)
		(in_bom yes)
		(on_board yes)
		(dnp no)
		(property "Reference" "C24"
			(at 342.265 131.445 90)
			(effects
				(font
					(size 1.27 1.27)
				)
				(justify right)
			)
		)
		(property "Value" "C_100n_0402"
			(at 351.79 115.57 0)
			(effects
				(font
					(size 1.27 1.27)
					(thickness 0.15)
				)
				(justify left bottom)
				(hide yes)
			)
		)
		(property "Footprint" "antmicro-footprints:C_0402_1005Metric"
			(at 354.33 115.57 0)
			(effects
				(font
					(size 1.27 1.27)
					(thickness 0.15)
				)
				(justify left bottom)
				(hide yes)
			)
		)
		(property "Datasheet" "https://www.murata.com/products/productdetail?partno=GRM155R61H104KE14%23"
			(at 356.87 115.57 0)
			(effects
				(font
					(size 1.27 1.27)
					(thickness 0.15)
				)
				(justify left bottom)
				(hide yes)
			)
		)
		(property "Description" "SMD Multilayer Ceramic Capacitor, 0.1 µF, 50 V, 0402 [1005 Metric], ± 10%, X5R, GRM Series"
			(at 341.63 135.89 0)
			(effects
				(font
					(size 1.27 1.27)
				)
				(hide yes)
			)
		)
		(property "Manufacturer" "Murata"
			(at 361.95 115.57 0)
			(effects
				(font
					(size 1.27 1.27)
					(thickness 0.15)
				)
				(justify left bottom)
				(hide yes)
			)
		)
		(property "MPN" "GRM155R61H104KE14D"
			(at 359.41 115.57 0)
			(effects
				(font
					(size 1.27 1.27)
					(thickness 0.15)
				)
				(justify left bottom)
				(hide yes)
			)
		)
		(property "Val" "100n"
			(at 342.265 135.255 90)
			(effects
				(font
					(size 1.27 1.27)
					(thickness 0.15)
				)
				(justify right)
			)
		)
		(property "License" "Apache-2.0"
			(at 364.49 115.57 0)
			(effects
				(font
					(size 1.27 1.27)
					(thickness 0.15)
				)
				(justify left bottom)
				(hide yes)
			)
		)
		(property "Author" "Antmicro"
			(at 367.03 115.57 0)
			(effects
				(font
					(size 1.27 1.27)
					(thickness 0.15)
				)
				(justify left bottom)
				(hide yes)
			)
		)
		(property "Voltage" "50V"
			(at 369.57 115.57 0)
			(effects
				(font
					(size 1.27 1.27)
				)
				(justify left bottom)
				(hide yes)
			)
		)
		(property "Dielectric" "X5R"
			(at 372.11 115.57 0)
			(effects
				(font
					(size 1.27 1.27)
				)
				(justify left bottom)
				(hide yes)
			)
		)
		(pin "1"
		)
		(pin "2"
		)
		(instances
			(project "artix-dc-scm"
				(path ""
					(reference "C24")
					(unit 1)
				)
			)
		)
	)
	(symbol
		(lib_id "antmicroCapacitors0402:C_4u7_0402")
		(at 309.88 135.89 90)
		(unit 1)
		(exclude_from_sim no)
		(in_bom yes)
		(on_board yes)
		(dnp no)
		(property "Reference" "C222"
			(at 310.515 131.445 90)
			(effects
				(font
					(size 1.27 1.27)
				)
				(justify right)
			)
		)
		(property "Value" "C_4u7_0402"
			(at 320.04 115.57 0)
			(effects
				(font
					(size 1.27 1.27)
					(thickness 0.15)
				)
				(justify left bottom)
				(hide yes)
			)
		)
		(property "Footprint" "antmicro-footprints:C_0402_1005Metric"
			(at 322.58 115.57 0)
			(effects
				(font
					(size 1.27 1.27)
					(thickness 0.15)
				)
				(justify left bottom)
				(hide yes)
			)
		)
		(property "Datasheet" "https://www.murata.com/products/productdetail?partno=GRM155R61A475MEAA%23"
			(at 325.12 115.57 0)
			(effects
				(font
					(size 1.27 1.27)
					(thickness 0.15)
				)
				(justify left bottom)
				(hide yes)
			)
		)
		(property "Description" "SMD Multilayer Ceramic Capacitor, 4.7 µF, 10 V, 0402 [1005 Metric], ± 20%, X5R, GRM Series"
			(at 309.88 135.89 0)
			(effects
				(font
					(size 1.27 1.27)
				)
				(hide yes)
			)
		)
		(property "Manufacturer" "Murata"
			(at 330.2 115.57 0)
			(effects
				(font
					(size 1.27 1.27)
					(thickness 0.15)
				)
				(justify left bottom)
				(hide yes)
			)
		)
		(property "MPN" "GRM155R61A475MEAAD"
			(at 327.66 115.57 0)
			(effects
				(font
					(size 1.27 1.27)
					(thickness 0.15)
				)
				(justify left bottom)
				(hide yes)
			)
		)
		(property "Val" "4u7"
			(at 310.515 135.255 90)
			(effects
				(font
					(size 1.27 1.27)
					(thickness 0.15)
				)
				(justify right)
			)
		)
		(property "License" "Apache-2.0"
			(at 332.74 115.57 0)
			(effects
				(font
					(size 1.27 1.27)
					(thickness 0.15)
				)
				(justify left bottom)
				(hide yes)
			)
		)
		(property "Author" "Antmicro"
			(at 335.28 115.57 0)
			(effects
				(font
					(size 1.27 1.27)
					(thickness 0.15)
				)
				(justify left bottom)
				(hide yes)
			)
		)
		(property "Voltage" ""
			(at 337.82 115.57 0)
			(effects
				(font
					(size 1.27 1.27)
				)
				(justify left bottom)
				(hide yes)
			)
		)
		(property "Dielectric" ""
			(at 340.36 115.57 0)
			(effects
				(font
					(size 1.27 1.27)
				)
				(justify left bottom)
				(hide yes)
			)
		)
		(pin "1"
		)
		(pin "2"
		)
		(instances
			(project "artix-dc-scm"
				(path ""
					(reference "C222")
					(unit 1)
				)
			)
		)
	)
	(symbol
		(lib_id "antmicroResistors0402:R_200k_0402")
		(at 223.52 213.36 270)
		(mirror x)
		(unit 1)
		(exclude_from_sim no)
		(in_bom yes)
		(on_board yes)
		(dnp no)
		(property "Reference" "R62"
			(at 224.79 209.55 90)
			(effects
				(font
					(size 1.27 1.27)
				)
				(justify left)
			)
		)
		(property "Value" "R_200k_0402"
			(at 219.71 213.36 0)
			(effects
				(font
					(size 1.27 1.27)
				)
				(hide yes)
			)
		)
		(property "Footprint" "antmicro-footprints:R_0402_1005Metric"
			(at 208.28 193.04 0)
			(effects
				(font
					(size 1.27 1.27)
					(thickness 0.15)
				)
				(justify left bottom)
				(hide yes)
			)
		)
		(property "Datasheet" "https://www.bourns.com/docs/product-datasheets/cr.pdf"
			(at 205.74 193.04 0)
			(effects
				(font
					(size 1.27 1.27)
					(thickness 0.15)
				)
				(justify left bottom)
				(hide yes)
			)
		)
		(property "Description" "SMD Chip Resistor, 200 kohm, ± 1%, 62.5 mW, 0402 [1005 Metric], Thick Film, General Purpose"
			(at 223.52 213.36 0)
			(effects
				(font
					(size 1.27 1.27)
				)
				(hide yes)
			)
		)
		(property "Manufacturer" "Bourns"
			(at 200.66 193.04 0)
			(effects
				(font
					(size 1.27 1.27)
					(thickness 0.15)
				)
				(justify left bottom)
				(hide yes)
			)
		)
		(property "MPN" "CR0402-FX-2003GLF"
			(at 203.2 193.04 0)
			(effects
				(font
					(size 1.27 1.27)
					(thickness 0.15)
				)
				(justify left bottom)
				(hide yes)
			)
		)
		(property "Val" "200k"
			(at 224.79 212.09 90)
			(effects
				(font
					(size 1.27 1.27)
					(thickness 0.15)
				)
				(justify left)
			)
		)
		(property "License" "Apache-2.0"
			(at 198.12 193.04 0)
			(effects
				(font
					(size 1.27 1.27)
					(thickness 0.15)
				)
				(justify left bottom)
				(hide yes)
			)
		)
		(property "Author" "Antmicro"
			(at 195.58 193.04 0)
			(effects
				(font
					(size 1.27 1.27)
					(thickness 0.15)
				)
				(justify left bottom)
				(hide yes)
			)
		)
		(property "Tolerance" "1%"
			(at 213.36 193.04 0)
			(effects
				(font
					(size 1.27 1.27)
				)
				(justify left bottom)
				(hide yes)
			)
		)
		(pin "1"
		)
		(pin "2"
		)
		(instances
			(project "artix-dc-scm"
				(path ""
					(reference "R62")
					(unit 1)
				)
			)
		)
	)
	(symbol
		(lib_id "antmicroCapacitors0402:C_100n_0402")
		(at 393.7 134.62 90)
		(unit 1)
		(exclude_from_sim no)
		(in_bom yes)
		(on_board yes)
		(dnp no)
		(property "Reference" "C22"
			(at 394.335 130.175 90)
			(effects
				(font
					(size 1.27 1.27)
				)
				(justify right)
			)
		)
		(property "Value" "C_100n_0402"
			(at 403.86 114.3 0)
			(effects
				(font
					(size 1.27 1.27)
					(thickness 0.15)
				)
				(justify left bottom)
				(hide yes)
			)
		)
		(property "Footprint" "antmicro-footprints:C_0402_1005Metric"
			(at 406.4 114.3 0)
			(effects
				(font
					(size 1.27 1.27)
					(thickness 0.15)
				)
				(justify left bottom)
				(hide yes)
			)
		)
		(property "Datasheet" "https://www.murata.com/products/productdetail?partno=GRM155R61H104KE14%23"
			(at 408.94 114.3 0)
			(effects
				(font
					(size 1.27 1.27)
					(thickness 0.15)
				)
				(justify left bottom)
				(hide yes)
			)
		)
		(property "Description" "SMD Multilayer Ceramic Capacitor, 0.1 µF, 50 V, 0402 [1005 Metric], ± 10%, X5R, GRM Series"
			(at 393.7 134.62 0)
			(effects
				(font
					(size 1.27 1.27)
				)
				(hide yes)
			)
		)
		(property "Manufacturer" "Murata"
			(at 414.02 114.3 0)
			(effects
				(font
					(size 1.27 1.27)
					(thickness 0.15)
				)
				(justify left bottom)
				(hide yes)
			)
		)
		(property "MPN" "GRM155R61H104KE14D"
			(at 411.48 114.3 0)
			(effects
				(font
					(size 1.27 1.27)
					(thickness 0.15)
				)
				(justify left bottom)
				(hide yes)
			)
		)
		(property "Val" "100n"
			(at 394.335 133.985 90)
			(effects
				(font
					(size 1.27 1.27)
					(thickness 0.15)
				)
				(justify right)
			)
		)
		(property "License" "Apache-2.0"
			(at 416.56 114.3 0)
			(effects
				(font
					(size 1.27 1.27)
					(thickness 0.15)
				)
				(justify left bottom)
				(hide yes)
			)
		)
		(property "Author" "Antmicro"
			(at 419.1 114.3 0)
			(effects
				(font
					(size 1.27 1.27)
					(thickness 0.15)
				)
				(justify left bottom)
				(hide yes)
			)
		)
		(property "Voltage" "50V"
			(at 421.64 114.3 0)
			(effects
				(font
					(size 1.27 1.27)
				)
				(justify left bottom)
				(hide yes)
			)
		)
		(property "Dielectric" "X5R"
			(at 424.18 114.3 0)
			(effects
				(font
					(size 1.27 1.27)
				)
				(justify left bottom)
				(hide yes)
			)
		)
		(pin "1"
		)
		(pin "2"
		)
		(instances
			(project "artix-dc-scm"
				(path ""
					(reference "C22")
					(unit 1)
				)
			)
		)
	)
	(symbol
		(lib_id "antmicroCapacitors0402:C_100n_0402")
		(at 393.7 123.19 90)
		(unit 1)
		(exclude_from_sim no)
		(in_bom yes)
		(on_board yes)
		(dnp no)
		(property "Reference" "C26"
			(at 394.335 118.745 90)
			(effects
				(font
					(size 1.27 1.27)
				)
				(justify right)
			)
		)
		(property "Value" "C_100n_0402"
			(at 403.86 102.87 0)
			(effects
				(font
					(size 1.27 1.27)
					(thickness 0.15)
				)
				(justify left bottom)
				(hide yes)
			)
		)
		(property "Footprint" "antmicro-footprints:C_0402_1005Metric"
			(at 406.4 102.87 0)
			(effects
				(font
					(size 1.27 1.27)
					(thickness 0.15)
				)
				(justify left bottom)
				(hide yes)
			)
		)
		(property "Datasheet" "https://www.murata.com/products/productdetail?partno=GRM155R61H104KE14%23"
			(at 408.94 102.87 0)
			(effects
				(font
					(size 1.27 1.27)
					(thickness 0.15)
				)
				(justify left bottom)
				(hide yes)
			)
		)
		(property "Description" "SMD Multilayer Ceramic Capacitor, 0.1 µF, 50 V, 0402 [1005 Metric], ± 10%, X5R, GRM Series"
			(at 393.7 123.19 0)
			(effects
				(font
					(size 1.27 1.27)
				)
				(hide yes)
			)
		)
		(property "Manufacturer" "Murata"
			(at 414.02 102.87 0)
			(effects
				(font
					(size 1.27 1.27)
					(thickness 0.15)
				)
				(justify left bottom)
				(hide yes)
			)
		)
		(property "MPN" "GRM155R61H104KE14D"
			(at 411.48 102.87 0)
			(effects
				(font
					(size 1.27 1.27)
					(thickness 0.15)
				)
				(justify left bottom)
				(hide yes)
			)
		)
		(property "Val" "100n"
			(at 394.335 122.555 90)
			(effects
				(font
					(size 1.27 1.27)
					(thickness 0.15)
				)
				(justify right)
			)
		)
		(property "License" "Apache-2.0"
			(at 416.56 102.87 0)
			(effects
				(font
					(size 1.27 1.27)
					(thickness 0.15)
				)
				(justify left bottom)
				(hide yes)
			)
		)
		(property "Author" "Antmicro"
			(at 419.1 102.87 0)
			(effects
				(font
					(size 1.27 1.27)
					(thickness 0.15)
				)
				(justify left bottom)
				(hide yes)
			)
		)
		(property "Voltage" "50V"
			(at 421.64 102.87 0)
			(effects
				(font
					(size 1.27 1.27)
				)
				(justify left bottom)
				(hide yes)
			)
		)
		(property "Dielectric" "X5R"
			(at 424.18 102.87 0)
			(effects
				(font
					(size 1.27 1.27)
				)
				(justify left bottom)
				(hide yes)
			)
		)
		(pin "1"
		)
		(pin "2"
		)
		(instances
			(project "artix-dc-scm"
				(path ""
					(reference "C26")
					(unit 1)
				)
			)
		)
	)
	(symbol
		(lib_id "antmicroCapacitorsmisc:C_100n_6V3_0402")
		(at 36.83 53.34 0)
		(unit 1)
		(exclude_from_sim no)
		(in_bom yes)
		(on_board yes)
		(dnp no)
		(property "Reference" "C195"
			(at 45.085 52.07 0)
			(effects
				(font
					(size 1.27 1.27)
				)
			)
		)
		(property "Value" "C_100n_6V3_0402"
			(at 57.15 63.5 0)
			(effects
				(font
					(size 1.27 1.27)
					(thickness 0.15)
				)
				(justify left bottom)
				(hide yes)
			)
		)
		(property "Footprint" "antmicro-footprints:C_0402_1005Metric"
			(at 57.15 66.04 0)
			(effects
				(font
					(size 1.27 1.27)
					(thickness 0.15)
				)
				(justify left bottom)
				(hide yes)
			)
		)
		(property "Datasheet" "https://www.passivecomponent.com/wp-content/uploads/datasheet/WTC_MLCC_General_Purpose.pdf"
			(at 57.15 68.58 0)
			(effects
				(font
					(size 1.27 1.27)
					(thickness 0.15)
				)
				(justify left bottom)
				(hide yes)
			)
		)
		(property "Description" "SMT Multilayer Ceramic Capacitor, 0.1 µF, 6.3 V, 0402 [1005 Metric], ± 10%, X5R, Walsin MLCC"
			(at 36.83 53.34 0)
			(effects
				(font
					(size 1.27 1.27)
				)
				(hide yes)
			)
		)
		(property "Manufacturer" "Walsin"
			(at 57.15 73.66 0)
			(effects
				(font
					(size 1.27 1.27)
					(thickness 0.15)
				)
				(justify left bottom)
				(hide yes)
			)
		)
		(property "MPN" "0402X104K6R3CT"
			(at 57.15 71.12 0)
			(effects
				(font
					(size 1.27 1.27)
					(thickness 0.15)
				)
				(justify left bottom)
				(hide yes)
			)
		)
		(property "Val" "100n"
			(at 33.02 53.34 0)
			(effects
				(font
					(size 1.27 1.27)
					(thickness 0.15)
				)
				(justify left bottom)
			)
		)
		(property "License" "Apache-2.0"
			(at 57.15 76.2 0)
			(effects
				(font
					(size 1.27 1.27)
					(thickness 0.15)
				)
				(justify left bottom)
				(hide yes)
			)
		)
		(property "Author" "Antmicro"
			(at 57.15 78.74 0)
			(effects
				(font
					(size 1.27 1.27)
					(thickness 0.15)
				)
				(justify left bottom)
				(hide yes)
			)
		)
		(property "Voltage" ""
			(at 57.15 81.28 0)
			(effects
				(font
					(size 1.27 1.27)
				)
				(justify left bottom)
				(hide yes)
			)
		)
		(property "Dielectric" ""
			(at 57.15 83.82 0)
			(effects
				(font
					(size 1.27 1.27)
				)
				(justify left bottom)
				(hide yes)
			)
		)
		(property "Public" "False"
			(at 57.15 86.36 0)
			(effects
				(font
					(size 1.27 1.27)
				)
				(justify left bottom)
				(hide yes)
			)
		)
		(pin "1"
		)
		(pin "2"
		)
		(instances
			(project "artix-dc-scm"
				(path ""
					(reference "C195")
					(unit 1)
				)
			)
		)
	)
	(symbol
		(lib_id "antmicroCapacitorsmisc:C_100n_6V3_0402")
		(at 39.37 55.88 0)
		(unit 1)
		(exclude_from_sim no)
		(in_bom yes)
		(on_board yes)
		(dnp no)
		(property "Reference" "C194"
			(at 45.72 54.61 0)
			(effects
				(font
					(size 1.27 1.27)
				)
			)
		)
		(property "Value" "C_100n_6V3_0402"
			(at 59.69 66.04 0)
			(effects
				(font
					(size 1.27 1.27)
					(thickness 0.15)
				)
				(justify left bottom)
				(hide yes)
			)
		)
		(property "Footprint" "antmicro-footprints:C_0402_1005Metric"
			(at 59.69 68.58 0)
			(effects
				(font
					(size 1.27 1.27)
					(thickness 0.15)
				)
				(justify left bottom)
				(hide yes)
			)
		)
		(property "Datasheet" "https://www.passivecomponent.com/wp-content/uploads/datasheet/WTC_MLCC_General_Purpose.pdf"
			(at 59.69 71.12 0)
			(effects
				(font
					(size 1.27 1.27)
					(thickness 0.15)
				)
				(justify left bottom)
				(hide yes)
			)
		)
		(property "Description" "SMT Multilayer Ceramic Capacitor, 0.1 µF, 6.3 V, 0402 [1005 Metric], ± 10%, X5R, Walsin MLCC"
			(at 39.37 55.88 0)
			(effects
				(font
					(size 1.27 1.27)
				)
				(hide yes)
			)
		)
		(property "Manufacturer" "Walsin"
			(at 59.69 76.2 0)
			(effects
				(font
					(size 1.27 1.27)
					(thickness 0.15)
				)
				(justify left bottom)
				(hide yes)
			)
		)
		(property "MPN" "0402X104K6R3CT"
			(at 59.69 73.66 0)
			(effects
				(font
					(size 1.27 1.27)
					(thickness 0.15)
				)
				(justify left bottom)
				(hide yes)
			)
		)
		(property "Val" "100n"
			(at 33.655 55.88 0)
			(effects
				(font
					(size 1.27 1.27)
					(thickness 0.15)
				)
				(justify left bottom)
			)
		)
		(property "License" "Apache-2.0"
			(at 59.69 78.74 0)
			(effects
				(font
					(size 1.27 1.27)
					(thickness 0.15)
				)
				(justify left bottom)
				(hide yes)
			)
		)
		(property "Author" "Antmicro"
			(at 59.69 81.28 0)
			(effects
				(font
					(size 1.27 1.27)
					(thickness 0.15)
				)
				(justify left bottom)
				(hide yes)
			)
		)
		(property "Voltage" ""
			(at 59.69 83.82 0)
			(effects
				(font
					(size 1.27 1.27)
				)
				(justify left bottom)
				(hide yes)
			)
		)
		(property "Dielectric" ""
			(at 59.69 86.36 0)
			(effects
				(font
					(size 1.27 1.27)
				)
				(justify left bottom)
				(hide yes)
			)
		)
		(property "Public" "False"
			(at 59.69 88.9 0)
			(effects
				(font
					(size 1.27 1.27)
				)
				(justify left bottom)
				(hide yes)
			)
		)
		(pin "1"
		)
		(pin "2"
		)
		(instances
			(project "artix-dc-scm"
				(path ""
					(reference "C194")
					(unit 1)
				)
			)
		)
	)
	(symbol
		(lib_id "antmicroCapacitors0402:C_100n_0402")
		(at 313.69 181.61 90)
		(unit 1)
		(exclude_from_sim no)
		(in_bom yes)
		(on_board yes)
		(dnp no)
		(property "Reference" "C4"
			(at 314.325 177.165 90)
			(effects
				(font
					(size 1.27 1.27)
				)
				(justify right)
			)
		)
		(property "Value" "C_100n_0402"
			(at 323.85 161.29 0)
			(effects
				(font
					(size 1.27 1.27)
					(thickness 0.15)
				)
				(justify left bottom)
				(hide yes)
			)
		)
		(property "Footprint" "antmicro-footprints:C_0402_1005Metric"
			(at 326.39 161.29 0)
			(effects
				(font
					(size 1.27 1.27)
					(thickness 0.15)
				)
				(justify left bottom)
				(hide yes)
			)
		)
		(property "Datasheet" "https://www.murata.com/products/productdetail?partno=GRM155R61H104KE14%23"
			(at 328.93 161.29 0)
			(effects
				(font
					(size 1.27 1.27)
					(thickness 0.15)
				)
				(justify left bottom)
				(hide yes)
			)
		)
		(property "Description" "SMD Multilayer Ceramic Capacitor, 0.1 µF, 50 V, 0402 [1005 Metric], ± 10%, X5R, GRM Series"
			(at 313.69 181.61 0)
			(effects
				(font
					(size 1.27 1.27)
				)
				(hide yes)
			)
		)
		(property "Manufacturer" "Murata"
			(at 334.01 161.29 0)
			(effects
				(font
					(size 1.27 1.27)
					(thickness 0.15)
				)
				(justify left bottom)
				(hide yes)
			)
		)
		(property "MPN" "GRM155R61H104KE14D"
			(at 331.47 161.29 0)
			(effects
				(font
					(size 1.27 1.27)
					(thickness 0.15)
				)
				(justify left bottom)
				(hide yes)
			)
		)
		(property "Val" "100n"
			(at 314.325 180.975 90)
			(effects
				(font
					(size 1.27 1.27)
					(thickness 0.15)
				)
				(justify right)
			)
		)
		(property "License" "Apache-2.0"
			(at 336.55 161.29 0)
			(effects
				(font
					(size 1.27 1.27)
					(thickness 0.15)
				)
				(justify left bottom)
				(hide yes)
			)
		)
		(property "Author" "Antmicro"
			(at 339.09 161.29 0)
			(effects
				(font
					(size 1.27 1.27)
					(thickness 0.15)
				)
				(justify left bottom)
				(hide yes)
			)
		)
		(property "Voltage" "50V"
			(at 341.63 161.29 0)
			(effects
				(font
					(size 1.27 1.27)
				)
				(justify left bottom)
				(hide yes)
			)
		)
		(property "Dielectric" "X5R"
			(at 344.17 161.29 0)
			(effects
				(font
					(size 1.27 1.27)
				)
				(justify left bottom)
				(hide yes)
			)
		)
		(pin "1"
		)
		(pin "2"
		)
		(instances
			(project "artix-dc-scm"
				(path ""
					(reference "C4")
					(unit 1)
				)
			)
		)
	)
	(symbol
		(lib_id "antmicropower:GND")
		(at 313.69 90.17 0)
		(unit 1)
		(exclude_from_sim no)
		(in_bom yes)
		(on_board yes)
		(dnp no)
		(property "Reference" "#PWR08"
			(at 313.69 96.52 0)
			(effects
				(font
					(size 1.27 1.27)
				)
				(hide yes)
			)
		)
		(property "Value" "GND"
			(at 313.69 93.98 0)
			(effects
				(font
					(size 1.27 1.27)
				)
			)
		)
		(property "Footprint" ""
			(at 313.69 90.17 0)
			(effects
				(font
					(size 1.27 1.27)
				)
				(hide yes)
			)
		)
		(property "Datasheet" ""
			(at 313.69 90.17 0)
			(effects
				(font
					(size 1.27 1.27)
				)
				(hide yes)
			)
		)
		(property "Description" ""
			(at 313.69 90.17 0)
			(effects
				(font
					(size 1.27 1.27)
				)
				(hide yes)
			)
		)
		(property "Author" "Antmicro"
			(at 322.58 97.79 0)
			(effects
				(font
					(size 1.27 1.27)
					(thickness 0.15)
				)
				(justify left bottom)
				(hide yes)
			)
		)
		(property "License" "Apache-2.0"
			(at 322.58 100.33 0)
			(effects
				(font
					(size 1.27 1.27)
					(thickness 0.15)
				)
				(justify left bottom)
				(hide yes)
			)
		)
		(pin "1"
		)
		(instances
			(project "artix-dc-scm"
				(path ""
					(reference "#PWR08")
					(unit 1)
				)
			)
		)
	)
	(symbol
		(lib_id "antmicroCapacitors0402:C_100n_0402")
		(at 313.69 85.09 270)
		(unit 1)
		(exclude_from_sim no)
		(in_bom yes)
		(on_board yes)
		(dnp no)
		(property "Reference" "C5"
			(at 314.325 85.725 90)
			(effects
				(font
					(size 1.27 1.27)
				)
				(justify left)
			)
		)
		(property "Value" "C_100n_0402"
			(at 303.53 105.41 0)
			(effects
				(font
					(size 1.27 1.27)
					(thickness 0.15)
				)
				(justify left bottom)
				(hide yes)
			)
		)
		(property "Footprint" "antmicro-footprints:C_0402_1005Metric"
			(at 300.99 105.41 0)
			(effects
				(font
					(size 1.27 1.27)
					(thickness 0.15)
				)
				(justify left bottom)
				(hide yes)
			)
		)
		(property "Datasheet" "https://www.murata.com/products/productdetail?partno=GRM155R61H104KE14%23"
			(at 298.45 105.41 0)
			(effects
				(font
					(size 1.27 1.27)
					(thickness 0.15)
				)
				(justify left bottom)
				(hide yes)
			)
		)
		(property "Description" "SMD Multilayer Ceramic Capacitor, 0.1 µF, 50 V, 0402 [1005 Metric], ± 10%, X5R, GRM Series"
			(at 313.69 85.09 0)
			(effects
				(font
					(size 1.27 1.27)
				)
				(hide yes)
			)
		)
		(property "Manufacturer" "Murata"
			(at 293.37 105.41 0)
			(effects
				(font
					(size 1.27 1.27)
					(thickness 0.15)
				)
				(justify left bottom)
				(hide yes)
			)
		)
		(property "MPN" "GRM155R61H104KE14D"
			(at 295.91 105.41 0)
			(effects
				(font
					(size 1.27 1.27)
					(thickness 0.15)
				)
				(justify left bottom)
				(hide yes)
			)
		)
		(property "Val" "100n"
			(at 314.325 89.535 90)
			(effects
				(font
					(size 1.27 1.27)
					(thickness 0.15)
				)
				(justify left)
			)
		)
		(property "License" "Apache-2.0"
			(at 290.83 105.41 0)
			(effects
				(font
					(size 1.27 1.27)
					(thickness 0.15)
				)
				(justify left bottom)
				(hide yes)
			)
		)
		(property "Author" "Antmicro"
			(at 288.29 105.41 0)
			(effects
				(font
					(size 1.27 1.27)
					(thickness 0.15)
				)
				(justify left bottom)
				(hide yes)
			)
		)
		(property "Voltage" "50V"
			(at 285.75 105.41 0)
			(effects
				(font
					(size 1.27 1.27)
				)
				(justify left bottom)
				(hide yes)
			)
		)
		(property "Dielectric" "X5R"
			(at 283.21 105.41 0)
			(effects
				(font
					(size 1.27 1.27)
				)
				(justify left bottom)
				(hide yes)
			)
		)
		(pin "1"
		)
		(pin "2"
		)
		(instances
			(project "artix-dc-scm"
				(path ""
					(reference "C5")
					(unit 1)
				)
			)
		)
	)
	(symbol
		(lib_id "antmicroMemory:MTFC16GAPALNA-AIT")
		(at 97.79 252.73 0)
		(mirror y)
		(unit 1)
		(exclude_from_sim no)
		(in_bom yes)
		(on_board yes)
		(dnp no)
		(fields_autoplaced yes)
		(property "Reference" "U1"
			(at 87.63 245.11 0)
			(effects
				(font
					(size 1.27 1.27)
				)
			)
		)
		(property "Value" "MTFC16GAPALNA-AIT"
			(at 87.63 247.65 0)
			(effects
				(font
					(size 1.27 1.27)
					(thickness 0.15)
				)
			)
		)
		(property "Footprint" "antmicro-footprints:BGA-170-100_18x14mm_Layout17x10_P1mm"
			(at 64.77 260.35 0)
			(effects
				(font
					(size 1.27 1.27)
					(thickness 0.15)
				)
				(justify left bottom)
				(hide yes)
			)
		)
		(property "Datasheet" "https://www.mouser.com/datasheet/2/671/micron_technology_mict-s-a0006806196-1-1759129.pdf"
			(at 64.77 262.89 0)
			(effects
				(font
					(size 1.27 1.27)
					(thickness 0.15)
				)
				(justify left bottom)
				(hide yes)
			)
		)
		(property "Description" "Managed NAND Flash Serial e-MMC 3.3V 128G-bit 128G/32G/16G x 1/4-bit/8-bit Automotive AEC-Q100 100-Pin TBGA Tray"
			(at 97.79 252.73 0)
			(effects
				(font
					(size 1.27 1.27)
				)
				(hide yes)
			)
		)
		(property "Manufacturer" "Micron Technology"
			(at 64.77 265.43 0)
			(effects
				(font
					(size 1.27 1.27)
					(thickness 0.15)
				)
				(justify left bottom)
				(hide yes)
			)
		)
		(property "MPN" "MTFC16GAPALNA-AIT"
			(at 64.77 267.97 0)
			(effects
				(font
					(size 1.27 1.27)
					(thickness 0.15)
				)
				(justify left bottom)
				(hide yes)
			)
		)
		(property "Author" "Antmicro"
			(at 64.77 270.51 0)
			(effects
				(font
					(size 1.27 1.27)
					(thickness 0.15)
				)
				(justify left bottom)
				(hide yes)
			)
		)
		(property "License" "Apache-2.0"
			(at 64.77 273.05 0)
			(effects
				(font
					(size 1.27 1.27)
					(thickness 0.15)
				)
				(justify left bottom)
				(hide yes)
			)
		)
		(pin "A1"
		)
		(pin "A10"
		)
		(pin "A2"
		)
		(pin "A9"
		)
		(pin "B1"
		)
		(pin "B10"
		)
		(pin "D2"
		)
		(pin "D3"
		)
		(pin "D4"
		)
		(pin "D5"
		)
		(pin "D6"
		)
		(pin "D7"
		)
		(pin "D8"
		)
		(pin "D9"
		)
		(pin "E2"
		)
		(pin "E3"
		)
		(pin "E4"
		)
		(pin "E5"
		)
		(pin "E6"
		)
		(pin "E7"
		)
		(pin "E8"
		)
		(pin "E9"
		)
		(pin "F2"
		)
		(pin "H2"
		)
		(pin "H3"
		)
		(pin "H4"
		)
		(pin "H5"
		)
		(pin "H6"
		)
		(pin "H7"
		)
		(pin "H8"
		)
		(pin "H9"
		)
		(pin "J2"
		)
		(pin "J3"
		)
		(pin "J4"
		)
		(pin "J6"
		)
		(pin "J7"
		)
		(pin "J8"
		)
		(pin "J9"
		)
		(pin "K2"
		)
		(pin "K3"
		)
		(pin "K4"
		)
		(pin "K5"
		)
		(pin "K6"
		)
		(pin "K7"
		)
		(pin "K8"
		)
		(pin "K9"
		)
		(pin "L2"
		)
		(pin "L3"
		)
		(pin "L4"
		)
		(pin "L5"
		)
		(pin "L6"
		)
		(pin "L7"
		)
		(pin "L8"
		)
		(pin "L9"
		)
		(pin "M2"
		)
		(pin "M3"
		)
		(pin "M4"
		)
		(pin "M5"
		)
		(pin "M6"
		)
		(pin "M7"
		)
		(pin "M8"
		)
		(pin "M9"
		)
		(pin "N2"
		)
		(pin "N3"
		)
		(pin "N4"
		)
		(pin "N5"
		)
		(pin "N6"
		)
		(pin "N7"
		)
		(pin "N8"
		)
		(pin "N9"
		)
		(pin "P2"
		)
		(pin "P3"
		)
		(pin "P4"
		)
		(pin "P5"
		)
		(pin "P6"
		)
		(pin "P7"
		)
		(pin "P8"
		)
		(pin "P9"
		)
		(pin "T1"
		)
		(pin "T10"
		)
		(pin "U1"
		)
		(pin "U10"
		)
		(pin "U2"
		)
		(pin "U9"
		)
		(pin "F3"
		)
		(pin "F4"
		)
		(pin "F5"
		)
		(pin "F6"
		)
		(pin "F7"
		)
		(pin "F8"
		)
		(pin "F9"
		)
		(pin "G2"
		)
		(pin "G3"
		)
		(pin "G4"
		)
		(pin "G5"
		)
		(pin "G6"
		)
		(pin "G7"
		)
		(pin "G8"
		)
		(pin "G9"
		)
		(pin "J5"
		)
		(instances
			(project "artix-dc-scm"
				(path ""
					(reference "U1")
					(unit 1)
				)
			)
		)
	)
	(symbol
		(lib_id "antmicroTestPoints:TP_1mm_SMD")
		(at 134.62 87.63 0)
		(unit 1)
		(exclude_from_sim no)
		(in_bom no)
		(on_board yes)
		(dnp no)
		(property "Reference" "TP7"
			(at 139.065 87.63 0)
			(effects
				(font
					(size 1.27 1.27)
				)
				(justify left)
			)
		)
		(property "Value" "TP_1mm_SMD"
			(at 134.62 90.17 0)
			(effects
				(font
					(size 1.27 1.27)
				)
				(hide yes)
			)
		)
		(property "Footprint" "antmicro-footprints:TP_SMD_1mm"
			(at 149.86 97.79 0)
			(effects
				(font
					(size 1.27 1.27)
					(thickness 0.15)
				)
				(justify left bottom)
				(hide yes)
			)
		)
		(property "Datasheet" ""
			(at 149.86 100.33 0)
			(effects
				(font
					(size 1.27 1.27)
					(thickness 0.15)
				)
				(justify left bottom)
				(hide yes)
			)
		)
		(property "Description" "Test point 1mm SMD"
			(at 134.62 87.63 0)
			(effects
				(font
					(size 1.27 1.27)
				)
				(hide yes)
			)
		)
		(property "MPN" ""
			(at 134.62 87.63 0)
			(effects
				(font
					(size 1.27 1.27)
				)
				(hide yes)
			)
		)
		(property "Manufacturer" ""
			(at 134.62 87.63 0)
			(effects
				(font
					(size 1.27 1.27)
				)
				(hide yes)
			)
		)
		(property "Author" "Antmicro"
			(at 149.86 102.87 0)
			(effects
				(font
					(size 1.27 1.27)
					(thickness 0.15)
				)
				(justify left bottom)
				(hide yes)
			)
		)
		(property "License" "Apache-2.0"
			(at 149.86 105.41 0)
			(effects
				(font
					(size 1.27 1.27)
					(thickness 0.15)
				)
				(justify left bottom)
				(hide yes)
			)
		)
		(pin "1"
		)
		(instances
			(project "artix-dc-scm"
				(path ""
					(reference "TP7")
					(unit 1)
				)
			)
		)
	)
	(symbol
		(lib_id "antmicroCapacitors0402:C_100n_0402")
		(at 214.63 213.36 90)
		(unit 1)
		(exclude_from_sim no)
		(in_bom yes)
		(on_board yes)
		(dnp no)
		(property "Reference" "C252"
			(at 215.265 208.915 90)
			(effects
				(font
					(size 1.27 1.27)
				)
				(justify right)
			)
		)
		(property "Value" "C_100n_0402"
			(at 224.79 193.04 0)
			(effects
				(font
					(size 1.27 1.27)
					(thickness 0.15)
				)
				(justify left bottom)
				(hide yes)
			)
		)
		(property "Footprint" "antmicro-footprints:C_0402_1005Metric"
			(at 227.33 193.04 0)
			(effects
				(font
					(size 1.27 1.27)
					(thickness 0.15)
				)
				(justify left bottom)
				(hide yes)
			)
		)
		(property "Datasheet" "https://www.murata.com/products/productdetail?partno=GRM155R61H104KE14%23"
			(at 229.87 193.04 0)
			(effects
				(font
					(size 1.27 1.27)
					(thickness 0.15)
				)
				(justify left bottom)
				(hide yes)
			)
		)
		(property "Description" "SMD Multilayer Ceramic Capacitor, 0.1 µF, 50 V, 0402 [1005 Metric], ± 10%, X5R, GRM Series"
			(at 214.63 213.36 0)
			(effects
				(font
					(size 1.27 1.27)
				)
				(hide yes)
			)
		)
		(property "Manufacturer" "Murata"
			(at 234.95 193.04 0)
			(effects
				(font
					(size 1.27 1.27)
					(thickness 0.15)
				)
				(justify left bottom)
				(hide yes)
			)
		)
		(property "MPN" "GRM155R61H104KE14D"
			(at 232.41 193.04 0)
			(effects
				(font
					(size 1.27 1.27)
					(thickness 0.15)
				)
				(justify left bottom)
				(hide yes)
			)
		)
		(property "Val" "100n"
			(at 215.265 212.725 90)
			(effects
				(font
					(size 1.27 1.27)
					(thickness 0.15)
				)
				(justify right)
			)
		)
		(property "License" "Apache-2.0"
			(at 237.49 193.04 0)
			(effects
				(font
					(size 1.27 1.27)
					(thickness 0.15)
				)
				(justify left bottom)
				(hide yes)
			)
		)
		(property "Author" "Antmicro"
			(at 240.03 193.04 0)
			(effects
				(font
					(size 1.27 1.27)
					(thickness 0.15)
				)
				(justify left bottom)
				(hide yes)
			)
		)
		(property "Voltage" "50V"
			(at 242.57 193.04 0)
			(effects
				(font
					(size 1.27 1.27)
				)
				(justify left bottom)
				(hide yes)
			)
		)
		(property "Dielectric" "X5R"
			(at 245.11 193.04 0)
			(effects
				(font
					(size 1.27 1.27)
				)
				(justify left bottom)
				(hide yes)
			)
		)
		(pin "1"
		)
		(pin "2"
		)
		(instances
			(project "artix-dc-scm"
				(path ""
					(reference "C252")
					(unit 1)
				)
			)
		)
	)
	(symbol
		(lib_id "antmicropower:GND")
		(at 214.63 213.36 0)
		(unit 1)
		(exclude_from_sim no)
		(in_bom yes)
		(on_board yes)
		(dnp no)
		(property "Reference" "#PWR0159"
			(at 214.63 219.71 0)
			(effects
				(font
					(size 1.27 1.27)
				)
				(hide yes)
			)
		)
		(property "Value" "GND"
			(at 214.63 217.17 0)
			(effects
				(font
					(size 1.27 1.27)
				)
			)
		)
		(property "Footprint" ""
			(at 214.63 213.36 0)
			(effects
				(font
					(size 1.27 1.27)
				)
				(hide yes)
			)
		)
		(property "Datasheet" ""
			(at 214.63 213.36 0)
			(effects
				(font
					(size 1.27 1.27)
				)
				(hide yes)
			)
		)
		(property "Description" ""
			(at 214.63 213.36 0)
			(effects
				(font
					(size 1.27 1.27)
				)
				(hide yes)
			)
		)
		(property "Author" "Antmicro"
			(at 223.52 220.98 0)
			(effects
				(font
					(size 1.27 1.27)
					(thickness 0.15)
				)
				(justify left bottom)
				(hide yes)
			)
		)
		(property "License" "Apache-2.0"
			(at 223.52 223.52 0)
			(effects
				(font
					(size 1.27 1.27)
					(thickness 0.15)
				)
				(justify left bottom)
				(hide yes)
			)
		)
		(pin "1"
		)
		(instances
			(project "artix-dc-scm"
				(path ""
					(reference "#PWR0159")
					(unit 1)
				)
			)
		)
	)
	(symbol
		(lib_id "antmicroResistors0402:R_4k7_0402")
		(at 173.99 95.25 180)
		(unit 1)
		(exclude_from_sim no)
		(in_bom yes)
		(on_board yes)
		(dnp no)
		(property "Reference" "R197"
			(at 171.45 92.71 0)
			(effects
				(font
					(size 1.27 1.27)
				)
			)
		)
		(property "Value" "R_4k7_0402"
			(at 153.67 82.55 0)
			(effects
				(font
					(size 1.27 1.27)
					(thickness 0.15)
				)
				(justify left bottom)
				(hide yes)
			)
		)
		(property "Footprint" "antmicro-footprints:R_0402_1005Metric"
			(at 153.67 80.01 0)
			(effects
				(font
					(size 1.27 1.27)
					(thickness 0.15)
				)
				(justify left bottom)
				(hide yes)
			)
		)
		(property "Datasheet" "https://www.bourns.com/docs/product-datasheets/cr.pdf"
			(at 153.67 77.47 0)
			(effects
				(font
					(size 1.27 1.27)
					(thickness 0.15)
				)
				(justify left bottom)
				(hide yes)
			)
		)
		(property "Description" "SMD Chip Resistor, 4.7 kohm, ± 1%, 62.5 mW, 0402 [1005 Metric], Thick Film, General Purpose"
			(at 173.99 95.25 0)
			(effects
				(font
					(size 1.27 1.27)
				)
				(hide yes)
			)
		)
		(property "Manufacturer" "Bourns"
			(at 153.67 72.39 0)
			(effects
				(font
					(size 1.27 1.27)
					(thickness 0.15)
				)
				(justify left bottom)
				(hide yes)
			)
		)
		(property "MPN" "CR0402-FX-4701GLF"
			(at 153.67 74.93 0)
			(effects
				(font
					(size 1.27 1.27)
					(thickness 0.15)
				)
				(justify left bottom)
				(hide yes)
			)
		)
		(property "Val" "4k7"
			(at 171.45 97.79 0)
			(effects
				(font
					(size 1.27 1.27)
					(thickness 0.15)
				)
			)
		)
		(property "License" "Apache-2.0"
			(at 153.67 69.85 0)
			(effects
				(font
					(size 1.27 1.27)
					(thickness 0.15)
				)
				(justify left bottom)
				(hide yes)
			)
		)
		(property "Author" "Antmicro"
			(at 153.67 67.31 0)
			(effects
				(font
					(size 1.27 1.27)
					(thickness 0.15)
				)
				(justify left bottom)
				(hide yes)
			)
		)
		(property "Tolerance" "1%"
			(at 153.67 85.09 0)
			(effects
				(font
					(size 1.27 1.27)
				)
				(justify left bottom)
				(hide yes)
			)
		)
		(pin "1"
		)
		(pin "2"
		)
		(instances
			(project "artix-dc-scm"
				(path ""
					(reference "R197")
					(unit 1)
				)
			)
		)
	)
	(symbol
		(lib_id "antmicroCapacitorsmisc:C_100n_6V3_0402")
		(at 27.94 250.19 90)
		(unit 1)
		(exclude_from_sim no)
		(in_bom yes)
		(on_board yes)
		(dnp no)
		(property "Reference" "C223"
			(at 28.575 245.745 90)
			(effects
				(font
					(size 1.27 1.27)
				)
				(justify right)
			)
		)
		(property "Value" "C_100n_6V3_0402"
			(at 38.1 229.87 0)
			(effects
				(font
					(size 1.27 1.27)
					(thickness 0.15)
				)
				(justify left bottom)
				(hide yes)
			)
		)
		(property "Footprint" "antmicro-footprints:C_0402_1005Metric"
			(at 40.64 229.87 0)
			(effects
				(font
					(size 1.27 1.27)
					(thickness 0.15)
				)
				(justify left bottom)
				(hide yes)
			)
		)
		(property "Datasheet" "https://www.passivecomponent.com/wp-content/uploads/datasheet/WTC_MLCC_General_Purpose.pdf"
			(at 43.18 229.87 0)
			(effects
				(font
					(size 1.27 1.27)
					(thickness 0.15)
				)
				(justify left bottom)
				(hide yes)
			)
		)
		(property "Description" "SMT Multilayer Ceramic Capacitor, 0.1 µF, 6.3 V, 0402 [1005 Metric], ± 10%, X5R, Walsin MLCC"
			(at 27.94 250.19 0)
			(effects
				(font
					(size 1.27 1.27)
				)
				(hide yes)
			)
		)
		(property "Manufacturer" "Walsin"
			(at 48.26 229.87 0)
			(effects
				(font
					(size 1.27 1.27)
					(thickness 0.15)
				)
				(justify left bottom)
				(hide yes)
			)
		)
		(property "MPN" "0402X104K6R3CT"
			(at 45.72 229.87 0)
			(effects
				(font
					(size 1.27 1.27)
					(thickness 0.15)
				)
				(justify left bottom)
				(hide yes)
			)
		)
		(property "Val" "100n"
			(at 28.575 249.555 90)
			(effects
				(font
					(size 1.27 1.27)
					(thickness 0.15)
				)
				(justify right)
			)
		)
		(property "License" "Apache-2.0"
			(at 50.8 229.87 0)
			(effects
				(font
					(size 1.27 1.27)
					(thickness 0.15)
				)
				(justify left bottom)
				(hide yes)
			)
		)
		(property "Author" "Antmicro"
			(at 53.34 229.87 0)
			(effects
				(font
					(size 1.27 1.27)
					(thickness 0.15)
				)
				(justify left bottom)
				(hide yes)
			)
		)
		(property "Voltage" ""
			(at 55.88 229.87 0)
			(effects
				(font
					(size 1.27 1.27)
				)
				(justify left bottom)
				(hide yes)
			)
		)
		(property "Dielectric" ""
			(at 58.42 229.87 0)
			(effects
				(font
					(size 1.27 1.27)
				)
				(justify left bottom)
				(hide yes)
			)
		)
		(property "Public" "False"
			(at 60.96 229.87 0)
			(effects
				(font
					(size 1.27 1.27)
				)
				(justify left bottom)
				(hide yes)
			)
		)
		(pin "1"
		)
		(pin "2"
		)
		(instances
			(project "artix-dc-scm"
				(path ""
					(reference "C223")
					(unit 1)
				)
			)
		)
	)
	(symbol
		(lib_id "antmicroCapacitors0402:C_100n_0402")
		(at 214.63 165.1 90)
		(unit 1)
		(exclude_from_sim no)
		(in_bom yes)
		(on_board yes)
		(dnp no)
		(property "Reference" "C251"
			(at 215.265 160.655 90)
			(effects
				(font
					(size 1.27 1.27)
				)
				(justify right)
			)
		)
		(property "Value" "C_100n_0402"
			(at 224.79 144.78 0)
			(effects
				(font
					(size 1.27 1.27)
					(thickness 0.15)
				)
				(justify left bottom)
				(hide yes)
			)
		)
		(property "Footprint" "antmicro-footprints:C_0402_1005Metric"
			(at 227.33 144.78 0)
			(effects
				(font
					(size 1.27 1.27)
					(thickness 0.15)
				)
				(justify left bottom)
				(hide yes)
			)
		)
		(property "Datasheet" "https://www.murata.com/products/productdetail?partno=GRM155R61H104KE14%23"
			(at 229.87 144.78 0)
			(effects
				(font
					(size 1.27 1.27)
					(thickness 0.15)
				)
				(justify left bottom)
				(hide yes)
			)
		)
		(property "Description" "SMD Multilayer Ceramic Capacitor, 0.1 µF, 50 V, 0402 [1005 Metric], ± 10%, X5R, GRM Series"
			(at 214.63 165.1 0)
			(effects
				(font
					(size 1.27 1.27)
				)
				(hide yes)
			)
		)
		(property "Manufacturer" "Murata"
			(at 234.95 144.78 0)
			(effects
				(font
					(size 1.27 1.27)
					(thickness 0.15)
				)
				(justify left bottom)
				(hide yes)
			)
		)
		(property "MPN" "GRM155R61H104KE14D"
			(at 232.41 144.78 0)
			(effects
				(font
					(size 1.27 1.27)
					(thickness 0.15)
				)
				(justify left bottom)
				(hide yes)
			)
		)
		(property "Val" "100n"
			(at 215.265 164.465 90)
			(effects
				(font
					(size 1.27 1.27)
					(thickness 0.15)
				)
				(justify right)
			)
		)
		(property "License" "Apache-2.0"
			(at 237.49 144.78 0)
			(effects
				(font
					(size 1.27 1.27)
					(thickness 0.15)
				)
				(justify left bottom)
				(hide yes)
			)
		)
		(property "Author" "Antmicro"
			(at 240.03 144.78 0)
			(effects
				(font
					(size 1.27 1.27)
					(thickness 0.15)
				)
				(justify left bottom)
				(hide yes)
			)
		)
		(property "Voltage" "50V"
			(at 242.57 144.78 0)
			(effects
				(font
					(size 1.27 1.27)
				)
				(justify left bottom)
				(hide yes)
			)
		)
		(property "Dielectric" "X5R"
			(at 245.11 144.78 0)
			(effects
				(font
					(size 1.27 1.27)
				)
				(justify left bottom)
				(hide yes)
			)
		)
		(pin "1"
		)
		(pin "2"
		)
		(instances
			(project "artix-dc-scm"
				(path ""
					(reference "C251")
					(unit 1)
				)
			)
		)
	)
	(symbol
		(lib_id "antmicropower:GND")
		(at 214.63 165.1 0)
		(unit 1)
		(exclude_from_sim no)
		(in_bom yes)
		(on_board yes)
		(dnp no)
		(property "Reference" "#PWR0158"
			(at 214.63 171.45 0)
			(effects
				(font
					(size 1.27 1.27)
				)
				(hide yes)
			)
		)
		(property "Value" "GND"
			(at 214.63 168.91 0)
			(effects
				(font
					(size 1.27 1.27)
				)
			)
		)
		(property "Footprint" ""
			(at 214.63 165.1 0)
			(effects
				(font
					(size 1.27 1.27)
				)
				(hide yes)
			)
		)
		(property "Datasheet" ""
			(at 214.63 165.1 0)
			(effects
				(font
					(size 1.27 1.27)
				)
				(hide yes)
			)
		)
		(property "Description" ""
			(at 214.63 165.1 0)
			(effects
				(font
					(size 1.27 1.27)
				)
				(hide yes)
			)
		)
		(property "Author" "Antmicro"
			(at 223.52 172.72 0)
			(effects
				(font
					(size 1.27 1.27)
					(thickness 0.15)
				)
				(justify left bottom)
				(hide yes)
			)
		)
		(property "License" "Apache-2.0"
			(at 223.52 175.26 0)
			(effects
				(font
					(size 1.27 1.27)
					(thickness 0.15)
				)
				(justify left bottom)
				(hide yes)
			)
		)
		(pin "1"
		)
		(instances
			(project "artix-dc-scm"
				(path ""
					(reference "#PWR0158")
					(unit 1)
				)
			)
		)
	)
	(symbol
		(lib_id "antmicroCapacitorsmisc:C_100n_6V3_0402")
		(at 36.83 250.19 90)
		(unit 1)
		(exclude_from_sim no)
		(in_bom yes)
		(on_board yes)
		(dnp no)
		(property "Reference" "C224"
			(at 37.465 245.745 90)
			(effects
				(font
					(size 1.27 1.27)
				)
				(justify right)
			)
		)
		(property "Value" "C_100n_6V3_0402"
			(at 46.99 229.87 0)
			(effects
				(font
					(size 1.27 1.27)
					(thickness 0.15)
				)
				(justify left bottom)
				(hide yes)
			)
		)
		(property "Footprint" "antmicro-footprints:C_0402_1005Metric"
			(at 49.53 229.87 0)
			(effects
				(font
					(size 1.27 1.27)
					(thickness 0.15)
				)
				(justify left bottom)
				(hide yes)
			)
		)
		(property "Datasheet" "https://www.passivecomponent.com/wp-content/uploads/datasheet/WTC_MLCC_General_Purpose.pdf"
			(at 52.07 229.87 0)
			(effects
				(font
					(size 1.27 1.27)
					(thickness 0.15)
				)
				(justify left bottom)
				(hide yes)
			)
		)
		(property "Description" "SMT Multilayer Ceramic Capacitor, 0.1 µF, 6.3 V, 0402 [1005 Metric], ± 10%, X5R, Walsin MLCC"
			(at 36.83 250.19 0)
			(effects
				(font
					(size 1.27 1.27)
				)
				(hide yes)
			)
		)
		(property "Manufacturer" "Walsin"
			(at 57.15 229.87 0)
			(effects
				(font
					(size 1.27 1.27)
					(thickness 0.15)
				)
				(justify left bottom)
				(hide yes)
			)
		)
		(property "MPN" "0402X104K6R3CT"
			(at 54.61 229.87 0)
			(effects
				(font
					(size 1.27 1.27)
					(thickness 0.15)
				)
				(justify left bottom)
				(hide yes)
			)
		)
		(property "Val" "100n"
			(at 37.465 249.555 90)
			(effects
				(font
					(size 1.27 1.27)
					(thickness 0.15)
				)
				(justify right)
			)
		)
		(property "License" "Apache-2.0"
			(at 59.69 229.87 0)
			(effects
				(font
					(size 1.27 1.27)
					(thickness 0.15)
				)
				(justify left bottom)
				(hide yes)
			)
		)
		(property "Author" "Antmicro"
			(at 62.23 229.87 0)
			(effects
				(font
					(size 1.27 1.27)
					(thickness 0.15)
				)
				(justify left bottom)
				(hide yes)
			)
		)
		(property "Voltage" ""
			(at 64.77 229.87 0)
			(effects
				(font
					(size 1.27 1.27)
				)
				(justify left bottom)
				(hide yes)
			)
		)
		(property "Dielectric" ""
			(at 67.31 229.87 0)
			(effects
				(font
					(size 1.27 1.27)
				)
				(justify left bottom)
				(hide yes)
			)
		)
		(property "Public" "False"
			(at 69.85 229.87 0)
			(effects
				(font
					(size 1.27 1.27)
				)
				(justify left bottom)
				(hide yes)
			)
		)
		(pin "1"
		)
		(pin "2"
		)
		(instances
			(project "artix-dc-scm"
				(path ""
					(reference "C224")
					(unit 1)
				)
			)
		)
	)
	(symbol
		(lib_id "antmicroCapacitorsmisc:C_100n_6V3_0402")
		(at 46.99 250.19 90)
		(unit 1)
		(exclude_from_sim no)
		(in_bom yes)
		(on_board yes)
		(dnp no)
		(property "Reference" "C229"
			(at 47.625 245.745 90)
			(effects
				(font
					(size 1.27 1.27)
				)
				(justify right)
			)
		)
		(property "Value" "C_100n_6V3_0402"
			(at 57.15 229.87 0)
			(effects
				(font
					(size 1.27 1.27)
					(thickness 0.15)
				)
				(justify left bottom)
				(hide yes)
			)
		)
		(property "Footprint" "antmicro-footprints:C_0402_1005Metric"
			(at 59.69 229.87 0)
			(effects
				(font
					(size 1.27 1.27)
					(thickness 0.15)
				)
				(justify left bottom)
				(hide yes)
			)
		)
		(property "Datasheet" "https://www.passivecomponent.com/wp-content/uploads/datasheet/WTC_MLCC_General_Purpose.pdf"
			(at 62.23 229.87 0)
			(effects
				(font
					(size 1.27 1.27)
					(thickness 0.15)
				)
				(justify left bottom)
				(hide yes)
			)
		)
		(property "Description" "SMT Multilayer Ceramic Capacitor, 0.1 µF, 6.3 V, 0402 [1005 Metric], ± 10%, X5R, Walsin MLCC"
			(at 46.99 250.19 0)
			(effects
				(font
					(size 1.27 1.27)
				)
				(hide yes)
			)
		)
		(property "Manufacturer" "Walsin"
			(at 67.31 229.87 0)
			(effects
				(font
					(size 1.27 1.27)
					(thickness 0.15)
				)
				(justify left bottom)
				(hide yes)
			)
		)
		(property "MPN" "0402X104K6R3CT"
			(at 64.77 229.87 0)
			(effects
				(font
					(size 1.27 1.27)
					(thickness 0.15)
				)
				(justify left bottom)
				(hide yes)
			)
		)
		(property "Val" "100n"
			(at 47.625 249.555 90)
			(effects
				(font
					(size 1.27 1.27)
					(thickness 0.15)
				)
				(justify right)
			)
		)
		(property "License" "Apache-2.0"
			(at 69.85 229.87 0)
			(effects
				(font
					(size 1.27 1.27)
					(thickness 0.15)
				)
				(justify left bottom)
				(hide yes)
			)
		)
		(property "Author" "Antmicro"
			(at 72.39 229.87 0)
			(effects
				(font
					(size 1.27 1.27)
					(thickness 0.15)
				)
				(justify left bottom)
				(hide yes)
			)
		)
		(property "Voltage" ""
			(at 74.93 229.87 0)
			(effects
				(font
					(size 1.27 1.27)
				)
				(justify left bottom)
				(hide yes)
			)
		)
		(property "Dielectric" ""
			(at 77.47 229.87 0)
			(effects
				(font
					(size 1.27 1.27)
				)
				(justify left bottom)
				(hide yes)
			)
		)
		(property "Public" "False"
			(at 80.01 229.87 0)
			(effects
				(font
					(size 1.27 1.27)
				)
				(justify left bottom)
				(hide yes)
			)
		)
		(pin "1"
		)
		(pin "2"
		)
		(instances
			(project "artix-dc-scm"
				(path ""
					(reference "C229")
					(unit 1)
				)
			)
		)
	)
	(symbol
		(lib_id "antmicropower:GND")
		(at 46.99 250.19 0)
		(unit 1)
		(exclude_from_sim no)
		(in_bom yes)
		(on_board yes)
		(dnp no)
		(property "Reference" "#PWR0123"
			(at 46.99 256.54 0)
			(effects
				(font
					(size 1.27 1.27)
				)
				(hide yes)
			)
		)
		(property "Value" "GND"
			(at 46.99 254 0)
			(effects
				(font
					(size 1.27 1.27)
				)
			)
		)
		(property "Footprint" ""
			(at 46.99 250.19 0)
			(effects
				(font
					(size 1.27 1.27)
				)
				(hide yes)
			)
		)
		(property "Datasheet" ""
			(at 46.99 250.19 0)
			(effects
				(font
					(size 1.27 1.27)
				)
				(hide yes)
			)
		)
		(property "Description" ""
			(at 46.99 250.19 0)
			(effects
				(font
					(size 1.27 1.27)
				)
				(hide yes)
			)
		)
		(property "Author" "Antmicro"
			(at 55.88 257.81 0)
			(effects
				(font
					(size 1.27 1.27)
					(thickness 0.15)
				)
				(justify left bottom)
				(hide yes)
			)
		)
		(property "License" "Apache-2.0"
			(at 55.88 260.35 0)
			(effects
				(font
					(size 1.27 1.27)
					(thickness 0.15)
				)
				(justify left bottom)
				(hide yes)
			)
		)
		(pin "1"
		)
		(instances
			(project "artix-dc-scm"
				(path ""
					(reference "#PWR0123")
					(unit 1)
				)
			)
		)
	)
	(symbol
		(lib_id "antmicropower:GND")
		(at 36.83 250.19 0)
		(unit 1)
		(exclude_from_sim no)
		(in_bom yes)
		(on_board yes)
		(dnp no)
		(property "Reference" "#PWR0122"
			(at 36.83 256.54 0)
			(effects
				(font
					(size 1.27 1.27)
				)
				(hide yes)
			)
		)
		(property "Value" "GND"
			(at 36.83 254 0)
			(effects
				(font
					(size 1.27 1.27)
				)
			)
		)
		(property "Footprint" ""
			(at 36.83 250.19 0)
			(effects
				(font
					(size 1.27 1.27)
				)
				(hide yes)
			)
		)
		(property "Datasheet" ""
			(at 36.83 250.19 0)
			(effects
				(font
					(size 1.27 1.27)
				)
				(hide yes)
			)
		)
		(property "Description" ""
			(at 36.83 250.19 0)
			(effects
				(font
					(size 1.27 1.27)
				)
				(hide yes)
			)
		)
		(property "Author" "Antmicro"
			(at 45.72 257.81 0)
			(effects
				(font
					(size 1.27 1.27)
					(thickness 0.15)
				)
				(justify left bottom)
				(hide yes)
			)
		)
		(property "License" "Apache-2.0"
			(at 45.72 260.35 0)
			(effects
				(font
					(size 1.27 1.27)
					(thickness 0.15)
				)
				(justify left bottom)
				(hide yes)
			)
		)
		(pin "1"
		)
		(instances
			(project "artix-dc-scm"
				(path ""
					(reference "#PWR0122")
					(unit 1)
				)
			)
		)
	)
	(symbol
		(lib_id "antmicropower:GND")
		(at 27.94 250.19 0)
		(unit 1)
		(exclude_from_sim no)
		(in_bom yes)
		(on_board yes)
		(dnp no)
		(property "Reference" "#PWR0119"
			(at 27.94 256.54 0)
			(effects
				(font
					(size 1.27 1.27)
				)
				(hide yes)
			)
		)
		(property "Value" "GND"
			(at 27.94 254 0)
			(effects
				(font
					(size 1.27 1.27)
				)
			)
		)
		(property "Footprint" ""
			(at 27.94 250.19 0)
			(effects
				(font
					(size 1.27 1.27)
				)
				(hide yes)
			)
		)
		(property "Datasheet" ""
			(at 27.94 250.19 0)
			(effects
				(font
					(size 1.27 1.27)
				)
				(hide yes)
			)
		)
		(property "Description" ""
			(at 27.94 250.19 0)
			(effects
				(font
					(size 1.27 1.27)
				)
				(hide yes)
			)
		)
		(property "Author" "Antmicro"
			(at 36.83 257.81 0)
			(effects
				(font
					(size 1.27 1.27)
					(thickness 0.15)
				)
				(justify left bottom)
				(hide yes)
			)
		)
		(property "License" "Apache-2.0"
			(at 36.83 260.35 0)
			(effects
				(font
					(size 1.27 1.27)
					(thickness 0.15)
				)
				(justify left bottom)
				(hide yes)
			)
		)
		(pin "1"
		)
		(instances
			(project "artix-dc-scm"
				(path ""
					(reference "#PWR0119")
					(unit 1)
				)
			)
		)
	)
	(symbol
		(lib_id "antmicroCapacitorsmisc:C_100n_6V3_0402")
		(at 57.15 250.19 90)
		(unit 1)
		(exclude_from_sim no)
		(in_bom yes)
		(on_board yes)
		(dnp no)
		(property "Reference" "C230"
			(at 57.785 245.745 90)
			(effects
				(font
					(size 1.27 1.27)
				)
				(justify right)
			)
		)
		(property "Value" "C_100n_6V3_0402"
			(at 67.31 229.87 0)
			(effects
				(font
					(size 1.27 1.27)
					(thickness 0.15)
				)
				(justify left bottom)
				(hide yes)
			)
		)
		(property "Footprint" "antmicro-footprints:C_0402_1005Metric"
			(at 69.85 229.87 0)
			(effects
				(font
					(size 1.27 1.27)
					(thickness 0.15)
				)
				(justify left bottom)
				(hide yes)
			)
		)
		(property "Datasheet" "https://www.passivecomponent.com/wp-content/uploads/datasheet/WTC_MLCC_General_Purpose.pdf"
			(at 72.39 229.87 0)
			(effects
				(font
					(size 1.27 1.27)
					(thickness 0.15)
				)
				(justify left bottom)
				(hide yes)
			)
		)
		(property "Description" "SMT Multilayer Ceramic Capacitor, 0.1 µF, 6.3 V, 0402 [1005 Metric], ± 10%, X5R, Walsin MLCC"
			(at 57.15 250.19 0)
			(effects
				(font
					(size 1.27 1.27)
				)
				(hide yes)
			)
		)
		(property "Manufacturer" "Walsin"
			(at 77.47 229.87 0)
			(effects
				(font
					(size 1.27 1.27)
					(thickness 0.15)
				)
				(justify left bottom)
				(hide yes)
			)
		)
		(property "MPN" "0402X104K6R3CT"
			(at 74.93 229.87 0)
			(effects
				(font
					(size 1.27 1.27)
					(thickness 0.15)
				)
				(justify left bottom)
				(hide yes)
			)
		)
		(property "Val" "100n"
			(at 57.785 249.555 90)
			(effects
				(font
					(size 1.27 1.27)
					(thickness 0.15)
				)
				(justify right)
			)
		)
		(property "License" "Apache-2.0"
			(at 80.01 229.87 0)
			(effects
				(font
					(size 1.27 1.27)
					(thickness 0.15)
				)
				(justify left bottom)
				(hide yes)
			)
		)
		(property "Author" "Antmicro"
			(at 82.55 229.87 0)
			(effects
				(font
					(size 1.27 1.27)
					(thickness 0.15)
				)
				(justify left bottom)
				(hide yes)
			)
		)
		(property "Voltage" ""
			(at 85.09 229.87 0)
			(effects
				(font
					(size 1.27 1.27)
				)
				(justify left bottom)
				(hide yes)
			)
		)
		(property "Dielectric" ""
			(at 87.63 229.87 0)
			(effects
				(font
					(size 1.27 1.27)
				)
				(justify left bottom)
				(hide yes)
			)
		)
		(property "Public" "False"
			(at 90.17 229.87 0)
			(effects
				(font
					(size 1.27 1.27)
				)
				(justify left bottom)
				(hide yes)
			)
		)
		(pin "1"
		)
		(pin "2"
		)
		(instances
			(project "artix-dc-scm"
				(path ""
					(reference "C230")
					(unit 1)
				)
			)
		)
	)
	(symbol
		(lib_id "antmicroCapacitorsmisc:C_100n_6V3_0402")
		(at 66.04 250.19 90)
		(unit 1)
		(exclude_from_sim no)
		(in_bom yes)
		(on_board yes)
		(dnp no)
		(property "Reference" "C231"
			(at 66.675 245.745 90)
			(effects
				(font
					(size 1.27 1.27)
				)
				(justify right)
			)
		)
		(property "Value" "C_100n_6V3_0402"
			(at 76.2 229.87 0)
			(effects
				(font
					(size 1.27 1.27)
					(thickness 0.15)
				)
				(justify left bottom)
				(hide yes)
			)
		)
		(property "Footprint" "antmicro-footprints:C_0402_1005Metric"
			(at 78.74 229.87 0)
			(effects
				(font
					(size 1.27 1.27)
					(thickness 0.15)
				)
				(justify left bottom)
				(hide yes)
			)
		)
		(property "Datasheet" "https://www.passivecomponent.com/wp-content/uploads/datasheet/WTC_MLCC_General_Purpose.pdf"
			(at 81.28 229.87 0)
			(effects
				(font
					(size 1.27 1.27)
					(thickness 0.15)
				)
				(justify left bottom)
				(hide yes)
			)
		)
		(property "Description" "SMT Multilayer Ceramic Capacitor, 0.1 µF, 6.3 V, 0402 [1005 Metric], ± 10%, X5R, Walsin MLCC"
			(at 66.04 250.19 0)
			(effects
				(font
					(size 1.27 1.27)
				)
				(hide yes)
			)
		)
		(property "Manufacturer" "Walsin"
			(at 86.36 229.87 0)
			(effects
				(font
					(size 1.27 1.27)
					(thickness 0.15)
				)
				(justify left bottom)
				(hide yes)
			)
		)
		(property "MPN" "0402X104K6R3CT"
			(at 83.82 229.87 0)
			(effects
				(font
					(size 1.27 1.27)
					(thickness 0.15)
				)
				(justify left bottom)
				(hide yes)
			)
		)
		(property "Val" "100n"
			(at 66.675 249.555 90)
			(effects
				(font
					(size 1.27 1.27)
					(thickness 0.15)
				)
				(justify right)
			)
		)
		(property "License" "Apache-2.0"
			(at 88.9 229.87 0)
			(effects
				(font
					(size 1.27 1.27)
					(thickness 0.15)
				)
				(justify left bottom)
				(hide yes)
			)
		)
		(property "Author" "Antmicro"
			(at 91.44 229.87 0)
			(effects
				(font
					(size 1.27 1.27)
					(thickness 0.15)
				)
				(justify left bottom)
				(hide yes)
			)
		)
		(property "Voltage" ""
			(at 93.98 229.87 0)
			(effects
				(font
					(size 1.27 1.27)
				)
				(justify left bottom)
				(hide yes)
			)
		)
		(property "Dielectric" ""
			(at 96.52 229.87 0)
			(effects
				(font
					(size 1.27 1.27)
				)
				(justify left bottom)
				(hide yes)
			)
		)
		(property "Public" "False"
			(at 99.06 229.87 0)
			(effects
				(font
					(size 1.27 1.27)
				)
				(justify left bottom)
				(hide yes)
			)
		)
		(pin "1"
		)
		(pin "2"
		)
		(instances
			(project "artix-dc-scm"
				(path ""
					(reference "C231")
					(unit 1)
				)
			)
		)
	)
	(symbol
		(lib_id "antmicroCapacitorsmisc:C_100n_6V3_0402")
		(at 66.04 236.22 90)
		(unit 1)
		(exclude_from_sim no)
		(in_bom yes)
		(on_board yes)
		(dnp no)
		(property "Reference" "C232"
			(at 66.675 231.775 90)
			(effects
				(font
					(size 1.27 1.27)
				)
				(justify right)
			)
		)
		(property "Value" "C_100n_6V3_0402"
			(at 76.2 215.9 0)
			(effects
				(font
					(size 1.27 1.27)
					(thickness 0.15)
				)
				(justify left bottom)
				(hide yes)
			)
		)
		(property "Footprint" "antmicro-footprints:C_0402_1005Metric"
			(at 78.74 215.9 0)
			(effects
				(font
					(size 1.27 1.27)
					(thickness 0.15)
				)
				(justify left bottom)
				(hide yes)
			)
		)
		(property "Datasheet" "https://www.passivecomponent.com/wp-content/uploads/datasheet/WTC_MLCC_General_Purpose.pdf"
			(at 81.28 215.9 0)
			(effects
				(font
					(size 1.27 1.27)
					(thickness 0.15)
				)
				(justify left bottom)
				(hide yes)
			)
		)
		(property "Description" "SMT Multilayer Ceramic Capacitor, 0.1 µF, 6.3 V, 0402 [1005 Metric], ± 10%, X5R, Walsin MLCC"
			(at 66.04 236.22 0)
			(effects
				(font
					(size 1.27 1.27)
				)
				(hide yes)
			)
		)
		(property "Manufacturer" "Walsin"
			(at 86.36 215.9 0)
			(effects
				(font
					(size 1.27 1.27)
					(thickness 0.15)
				)
				(justify left bottom)
				(hide yes)
			)
		)
		(property "MPN" "0402X104K6R3CT"
			(at 83.82 215.9 0)
			(effects
				(font
					(size 1.27 1.27)
					(thickness 0.15)
				)
				(justify left bottom)
				(hide yes)
			)
		)
		(property "Val" "100n"
			(at 66.675 235.585 90)
			(effects
				(font
					(size 1.27 1.27)
					(thickness 0.15)
				)
				(justify right)
			)
		)
		(property "License" "Apache-2.0"
			(at 88.9 215.9 0)
			(effects
				(font
					(size 1.27 1.27)
					(thickness 0.15)
				)
				(justify left bottom)
				(hide yes)
			)
		)
		(property "Author" "Antmicro"
			(at 91.44 215.9 0)
			(effects
				(font
					(size 1.27 1.27)
					(thickness 0.15)
				)
				(justify left bottom)
				(hide yes)
			)
		)
		(property "Voltage" ""
			(at 93.98 215.9 0)
			(effects
				(font
					(size 1.27 1.27)
				)
				(justify left bottom)
				(hide yes)
			)
		)
		(property "Dielectric" ""
			(at 96.52 215.9 0)
			(effects
				(font
					(size 1.27 1.27)
				)
				(justify left bottom)
				(hide yes)
			)
		)
		(property "Public" "False"
			(at 99.06 215.9 0)
			(effects
				(font
					(size 1.27 1.27)
				)
				(justify left bottom)
				(hide yes)
			)
		)
		(pin "1"
		)
		(pin "2"
		)
		(instances
			(project "artix-dc-scm"
				(path ""
					(reference "C232")
					(unit 1)
				)
			)
		)
	)
	(symbol
		(lib_id "antmicropower:GND")
		(at 66.04 236.22 0)
		(unit 1)
		(exclude_from_sim no)
		(in_bom yes)
		(on_board yes)
		(dnp no)
		(property "Reference" "#PWR0126"
			(at 66.04 242.57 0)
			(effects
				(font
					(size 1.27 1.27)
				)
				(hide yes)
			)
		)
		(property "Value" "GND"
			(at 66.04 240.03 0)
			(effects
				(font
					(size 1.27 1.27)
				)
			)
		)
		(property "Footprint" ""
			(at 66.04 236.22 0)
			(effects
				(font
					(size 1.27 1.27)
				)
				(hide yes)
			)
		)
		(property "Datasheet" ""
			(at 66.04 236.22 0)
			(effects
				(font
					(size 1.27 1.27)
				)
				(hide yes)
			)
		)
		(property "Description" ""
			(at 66.04 236.22 0)
			(effects
				(font
					(size 1.27 1.27)
				)
				(hide yes)
			)
		)
		(property "Author" "Antmicro"
			(at 74.93 243.84 0)
			(effects
				(font
					(size 1.27 1.27)
					(thickness 0.15)
				)
				(justify left bottom)
				(hide yes)
			)
		)
		(property "License" "Apache-2.0"
			(at 74.93 246.38 0)
			(effects
				(font
					(size 1.27 1.27)
					(thickness 0.15)
				)
				(justify left bottom)
				(hide yes)
			)
		)
		(pin "1"
		)
		(instances
			(project "artix-dc-scm"
				(path ""
					(reference "#PWR0126")
					(unit 1)
				)
			)
		)
	)
	(symbol
		(lib_id "antmicropower:GND")
		(at 66.04 250.19 0)
		(unit 1)
		(exclude_from_sim no)
		(in_bom yes)
		(on_board yes)
		(dnp no)
		(property "Reference" "#PWR0125"
			(at 66.04 256.54 0)
			(effects
				(font
					(size 1.27 1.27)
				)
				(hide yes)
			)
		)
		(property "Value" "GND"
			(at 66.04 254 0)
			(effects
				(font
					(size 1.27 1.27)
				)
			)
		)
		(property "Footprint" ""
			(at 66.04 250.19 0)
			(effects
				(font
					(size 1.27 1.27)
				)
				(hide yes)
			)
		)
		(property "Datasheet" ""
			(at 66.04 250.19 0)
			(effects
				(font
					(size 1.27 1.27)
				)
				(hide yes)
			)
		)
		(property "Description" ""
			(at 66.04 250.19 0)
			(effects
				(font
					(size 1.27 1.27)
				)
				(hide yes)
			)
		)
		(property "Author" "Antmicro"
			(at 74.93 257.81 0)
			(effects
				(font
					(size 1.27 1.27)
					(thickness 0.15)
				)
				(justify left bottom)
				(hide yes)
			)
		)
		(property "License" "Apache-2.0"
			(at 74.93 260.35 0)
			(effects
				(font
					(size 1.27 1.27)
					(thickness 0.15)
				)
				(justify left bottom)
				(hide yes)
			)
		)
		(pin "1"
		)
		(instances
			(project "artix-dc-scm"
				(path ""
					(reference "#PWR0125")
					(unit 1)
				)
			)
		)
	)
	(symbol
		(lib_id "antmicropower:GND")
		(at 57.15 250.19 0)
		(unit 1)
		(exclude_from_sim no)
		(in_bom yes)
		(on_board yes)
		(dnp no)
		(property "Reference" "#PWR0124"
			(at 57.15 256.54 0)
			(effects
				(font
					(size 1.27 1.27)
				)
				(hide yes)
			)
		)
		(property "Value" "GND"
			(at 57.15 254 0)
			(effects
				(font
					(size 1.27 1.27)
				)
			)
		)
		(property "Footprint" ""
			(at 57.15 250.19 0)
			(effects
				(font
					(size 1.27 1.27)
				)
				(hide yes)
			)
		)
		(property "Datasheet" ""
			(at 57.15 250.19 0)
			(effects
				(font
					(size 1.27 1.27)
				)
				(hide yes)
			)
		)
		(property "Description" ""
			(at 57.15 250.19 0)
			(effects
				(font
					(size 1.27 1.27)
				)
				(hide yes)
			)
		)
		(property "Author" "Antmicro"
			(at 66.04 257.81 0)
			(effects
				(font
					(size 1.27 1.27)
					(thickness 0.15)
				)
				(justify left bottom)
				(hide yes)
			)
		)
		(property "License" "Apache-2.0"
			(at 66.04 260.35 0)
			(effects
				(font
					(size 1.27 1.27)
					(thickness 0.15)
				)
				(justify left bottom)
				(hide yes)
			)
		)
		(pin "1"
		)
		(instances
			(project "artix-dc-scm"
				(path ""
					(reference "#PWR0124")
					(unit 1)
				)
			)
		)
	)
	(symbol
		(lib_id "antmicropower:GND")
		(at 175.26 102.87 0)
		(unit 1)
		(exclude_from_sim no)
		(in_bom yes)
		(on_board yes)
		(dnp no)
		(property "Reference" "#PWR0168"
			(at 175.26 109.22 0)
			(effects
				(font
					(size 1.27 1.27)
				)
				(hide yes)
			)
		)
		(property "Value" "GND"
			(at 175.26 106.68 0)
			(effects
				(font
					(size 1.27 1.27)
				)
			)
		)
		(property "Footprint" ""
			(at 175.26 102.87 0)
			(effects
				(font
					(size 1.27 1.27)
				)
				(hide yes)
			)
		)
		(property "Datasheet" ""
			(at 175.26 102.87 0)
			(effects
				(font
					(size 1.27 1.27)
				)
				(hide yes)
			)
		)
		(property "Description" ""
			(at 175.26 102.87 0)
			(effects
				(font
					(size 1.27 1.27)
				)
				(hide yes)
			)
		)
		(property "Author" "Antmicro"
			(at 184.15 110.49 0)
			(effects
				(font
					(size 1.27 1.27)
					(thickness 0.15)
				)
				(justify left bottom)
				(hide yes)
			)
		)
		(property "License" "Apache-2.0"
			(at 184.15 113.03 0)
			(effects
				(font
					(size 1.27 1.27)
					(thickness 0.15)
				)
				(justify left bottom)
				(hide yes)
			)
		)
		(pin "1"
		)
		(instances
			(project "artix-dc-scm"
				(path ""
					(reference "#PWR0168")
					(unit 1)
				)
			)
		)
	)
	(symbol
		(lib_id "antmicroResistors0402:R_12k_0402")
		(at 347.98 177.8 0)
		(unit 1)
		(exclude_from_sim no)
		(in_bom yes)
		(on_board yes)
		(dnp no)
		(property "Reference" "R7"
			(at 353.06 176.53 0)
			(effects
				(font
					(size 1.27 1.27)
				)
				(justify left)
			)
		)
		(property "Value" "R_12k_0402"
			(at 368.3 190.5 0)
			(effects
				(font
					(size 1.27 1.27)
					(thickness 0.15)
				)
				(justify left bottom)
				(hide yes)
			)
		)
		(property "Footprint" "antmicro-footprints:R_0402_1005Metric"
			(at 368.3 193.04 0)
			(effects
				(font
					(size 1.27 1.27)
					(thickness 0.15)
				)
				(justify left bottom)
				(hide yes)
			)
		)
		(property "Datasheet" "https://www.bourns.com/docs/product-datasheets/cr.pdf"
			(at 368.3 195.58 0)
			(effects
				(font
					(size 1.27 1.27)
					(thickness 0.15)
				)
				(justify left bottom)
				(hide yes)
			)
		)
		(property "Description" "SMD Chip Resistor, 12 kohm, ± 1%, 62.5 mW, 0402 [1005 Metric], Thick Film, General Purpose"
			(at 347.98 177.8 0)
			(effects
				(font
					(size 1.27 1.27)
				)
				(hide yes)
			)
		)
		(property "Manufacturer" "Bourns"
			(at 368.3 200.66 0)
			(effects
				(font
					(size 1.27 1.27)
					(thickness 0.15)
				)
				(justify left bottom)
				(hide yes)
			)
		)
		(property "MPN" "CR0402-FX-1202GLF"
			(at 368.3 198.12 0)
			(effects
				(font
					(size 1.27 1.27)
					(thickness 0.15)
				)
				(justify left bottom)
				(hide yes)
			)
		)
		(property "Val" "12k"
			(at 346.71 176.53 0)
			(effects
				(font
					(size 1.27 1.27)
					(thickness 0.15)
				)
			)
		)
		(property "License" "Apache-2.0"
			(at 368.3 203.2 0)
			(effects
				(font
					(size 1.27 1.27)
					(thickness 0.15)
				)
				(justify left bottom)
				(hide yes)
			)
		)
		(property "Author" "Antmicro"
			(at 368.3 205.74 0)
			(effects
				(font
					(size 1.27 1.27)
					(thickness 0.15)
				)
				(justify left bottom)
				(hide yes)
			)
		)
		(property "Tolerance" "1%"
			(at 368.3 187.96 0)
			(effects
				(font
					(size 1.27 1.27)
				)
				(justify left bottom)
				(hide yes)
			)
		)
		(pin "1"
		)
		(pin "2"
		)
		(instances
			(project "artix-dc-scm"
				(path ""
					(reference "R7")
					(unit 1)
				)
			)
		)
	)
	(symbol
		(lib_id "antmicroResistors0402:R_0R_0402")
		(at 349.25 137.16 90)
		(unit 1)
		(exclude_from_sim no)
		(in_bom yes)
		(on_board yes)
		(dnp no)
		(property "Reference" "R11"
			(at 350.52 133.35 90)
			(effects
				(font
					(size 1.27 1.27)
				)
				(justify right)
			)
		)
		(property "Value" "R_0R_0402"
			(at 361.95 116.84 0)
			(effects
				(font
					(size 1.27 1.27)
					(thickness 0.15)
				)
				(justify left bottom)
				(hide yes)
			)
		)
		(property "Footprint" "antmicro-footprints:R_0402_1005Metric"
			(at 364.49 116.84 0)
			(effects
				(font
					(size 1.27 1.27)
					(thickness 0.15)
				)
				(justify left bottom)
				(hide yes)
			)
		)
		(property "Datasheet" "https://industrial.panasonic.com/cdbs/www-data/pdf/RDA0000/AOA0000C301.pdf"
			(at 367.03 116.84 0)
			(effects
				(font
					(size 1.27 1.27)
					(thickness 0.15)
				)
				(justify left bottom)
				(hide yes)
			)
		)
		(property "Description" "SMD Chip Resistor, Jumper, 0 ohm, 100 mW, 0402 [1005 Metric], Thick Film, General Purpose"
			(at 349.25 137.16 0)
			(effects
				(font
					(size 1.27 1.27)
				)
				(hide yes)
			)
		)
		(property "Manufacturer" "Panasonic"
			(at 372.11 116.84 0)
			(effects
				(font
					(size 1.27 1.27)
					(thickness 0.15)
				)
				(justify left bottom)
				(hide yes)
			)
		)
		(property "MPN" "ERJ2GE0R00X"
			(at 369.57 116.84 0)
			(effects
				(font
					(size 1.27 1.27)
					(thickness 0.15)
				)
				(justify left bottom)
				(hide yes)
			)
		)
		(property "Val" "0R"
			(at 350.52 135.89 90)
			(effects
				(font
					(size 1.27 1.27)
					(thickness 0.15)
				)
				(justify right)
			)
		)
		(property "License" "Apache-2.0"
			(at 374.65 116.84 0)
			(effects
				(font
					(size 1.27 1.27)
					(thickness 0.15)
				)
				(justify left bottom)
				(hide yes)
			)
		)
		(property "Author" "Antmicro"
			(at 377.19 116.84 0)
			(effects
				(font
					(size 1.27 1.27)
					(thickness 0.15)
				)
				(justify left bottom)
				(hide yes)
			)
		)
		(property "Tolerance" "~"
			(at 359.41 116.84 0)
			(effects
				(font
					(size 1.27 1.27)
				)
				(justify left bottom)
				(hide yes)
			)
		)
		(property "Current" "1A"
			(at 351.155 137.1599 90)
			(effects
				(font
					(size 1.27 1.27)
					(thickness 0.15)
				)
				(justify right)
				(hide yes)
			)
		)
		(pin "1"
		)
		(pin "2"
		)
		(instances
			(project "artix-dc-scm"
				(path ""
					(reference "R11")
					(unit 1)
				)
			)
		)
	)
	(symbol
		(lib_id "antmicroFerriteBeadsandChips:FB_600Z_0.3A_Murata-BLM15AG_0402")
		(at 138.43 21.59 0)
		(unit 1)
		(exclude_from_sim no)
		(in_bom yes)
		(on_board yes)
		(dnp no)
		(property "Reference" "FB2"
			(at 140.97 13.97 0)
			(effects
				(font
					(size 1.27 1.27)
				)
			)
		)
		(property "Value" "FB_600Z_0.3A_Murata-BLM15AG_0402"
			(at 142.2018 18.415 90)
			(effects
				(font
					(size 1.27 1.27)
					(thickness 0.15)
				)
				(justify left)
				(hide yes)
			)
		)
		(property "Footprint" "antmicro-footprints:FB_0402_1005Metric"
			(at 152.4 26.67 0)
			(effects
				(font
					(size 1.27 1.27)
					(thickness 0.15)
				)
				(justify left bottom)
				(hide yes)
			)
		)
		(property "Datasheet" "https://www.murata.com/en-us/products/productdata/8796740059166/ENFA0018.pdf"
			(at 152.4 29.21 0)
			(effects
				(font
					(size 1.27 1.27)
					(thickness 0.15)
				)
				(justify left bottom)
				(hide yes)
			)
		)
		(property "Description" "Ferrite Bead, 0402 [1005 Metric], 600 ohm, 300 mA, BLM15AG_SN, 0.6 ohm, ± 25%, General use"
			(at 138.43 21.59 0)
			(effects
				(font
					(size 1.27 1.27)
				)
				(hide yes)
			)
		)
		(property "MPN" "BLM15AG601SN1D"
			(at 138.43 16.51 0)
			(effects
				(font
					(size 1.27 1.27)
					(thickness 0.15)
				)
			)
		)
		(property "Manufacturer" "Murata"
			(at 152.4 34.29 0)
			(effects
				(font
					(size 1.27 1.27)
					(thickness 0.15)
				)
				(justify left bottom)
				(hide yes)
			)
		)
		(property "Author" "Antmicro"
			(at 152.4 36.83 0)
			(effects
				(font
					(size 1.27 1.27)
					(thickness 0.15)
				)
				(justify left bottom)
				(hide yes)
			)
		)
		(property "License" "Apache-2.0"
			(at 152.4 39.37 0)
			(effects
				(font
					(size 1.27 1.27)
					(thickness 0.15)
				)
				(justify left bottom)
				(hide yes)
			)
		)
		(property "Val" "600Z/0.3A"
			(at 140.97 19.05 0)
			(effects
				(font
					(size 1.27 1.27)
				)
			)
		)
		(property "Current" ""
			(at 158.75 44.45 0)
			(effects
				(font
					(size 1.27 1.27)
					(thickness 0.15)
				)
				(justify left bottom)
				(hide yes)
			)
		)
		(pin "1"
		)
		(pin "2"
		)
		(instances
			(project "artix-dc-scm"
				(path ""
					(reference "FB2")
					(unit 1)
				)
			)
		)
	)
	(symbol
		(lib_id "antmicroFerriteBeadsandChips:FB_600Z_0.3A_Murata-BLM15AG_0402")
		(at 138.43 25.4 0)
		(unit 1)
		(exclude_from_sim no)
		(in_bom yes)
		(on_board yes)
		(dnp no)
		(property "Reference" "FB1"
			(at 140.97 27.94 0)
			(effects
				(font
					(size 1.27 1.27)
				)
			)
		)
		(property "Value" "FB_600Z_0.3A_Murata-BLM15AG_0402"
			(at 152.4 27.94 0)
			(effects
				(font
					(size 1.27 1.27)
					(thickness 0.15)
				)
				(justify left bottom)
				(hide yes)
			)
		)
		(property "Footprint" "antmicro-footprints:FB_0402_1005Metric"
			(at 152.4 30.48 0)
			(effects
				(font
					(size 1.27 1.27)
					(thickness 0.15)
				)
				(justify left bottom)
				(hide yes)
			)
		)
		(property "Datasheet" "https://www.murata.com/en-us/products/productdata/8796740059166/ENFA0018.pdf"
			(at 152.4 33.02 0)
			(effects
				(font
					(size 1.27 1.27)
					(thickness 0.15)
				)
				(justify left bottom)
				(hide yes)
			)
		)
		(property "Description" "Ferrite Bead, 0402 [1005 Metric], 600 ohm, 300 mA, BLM15AG_SN, 0.6 ohm, ± 25%, General use"
			(at 138.43 25.4 0)
			(effects
				(font
					(size 1.27 1.27)
				)
				(hide yes)
			)
		)
		(property "MPN" "BLM15AG601SN1D"
			(at 137.16 30.48 0)
			(effects
				(font
					(size 1.27 1.27)
					(thickness 0.15)
				)
			)
		)
		(property "Manufacturer" "Murata"
			(at 152.4 38.1 0)
			(effects
				(font
					(size 1.27 1.27)
					(thickness 0.15)
				)
				(justify left bottom)
				(hide yes)
			)
		)
		(property "Author" "Antmicro"
			(at 152.4 40.64 0)
			(effects
				(font
					(size 1.27 1.27)
					(thickness 0.15)
				)
				(justify left bottom)
				(hide yes)
			)
		)
		(property "License" "Apache-2.0"
			(at 152.4 43.18 0)
			(effects
				(font
					(size 1.27 1.27)
					(thickness 0.15)
				)
				(justify left bottom)
				(hide yes)
			)
		)
		(property "Val" "600Z/0.3A"
			(at 139.7 33.02 0)
			(effects
				(font
					(size 1.27 1.27)
				)
			)
		)
		(property "Current" ""
			(at 158.75 48.26 0)
			(effects
				(font
					(size 1.27 1.27)
					(thickness 0.15)
				)
				(justify left bottom)
				(hide yes)
			)
		)
		(pin "1"
		)
		(pin "2"
		)
		(instances
			(project "artix-dc-scm"
				(path ""
					(reference "FB1")
					(unit 1)
				)
			)
		)
	)
	(symbol
		(lib_id "antmicropower:GND")
		(at 74.93 279.4 0)
		(unit 1)
		(exclude_from_sim no)
		(in_bom yes)
		(on_board yes)
		(dnp no)
		(property "Reference" "#PWR088"
			(at 74.93 285.75 0)
			(effects
				(font
					(size 1.27 1.27)
				)
				(hide yes)
			)
		)
		(property "Value" "GND"
			(at 74.93 283.21 0)
			(effects
				(font
					(size 1.27 1.27)
				)
			)
		)
		(property "Footprint" ""
			(at 74.93 279.4 0)
			(effects
				(font
					(size 1.27 1.27)
				)
				(hide yes)
			)
		)
		(property "Datasheet" ""
			(at 74.93 279.4 0)
			(effects
				(font
					(size 1.27 1.27)
				)
				(hide yes)
			)
		)
		(property "Description" ""
			(at 74.93 279.4 0)
			(effects
				(font
					(size 1.27 1.27)
				)
				(hide yes)
			)
		)
		(property "Author" "Antmicro"
			(at 83.82 287.02 0)
			(effects
				(font
					(size 1.27 1.27)
					(thickness 0.15)
				)
				(justify left bottom)
				(hide yes)
			)
		)
		(property "License" "Apache-2.0"
			(at 83.82 289.56 0)
			(effects
				(font
					(size 1.27 1.27)
					(thickness 0.15)
				)
				(justify left bottom)
				(hide yes)
			)
		)
		(pin "1"
		)
		(instances
			(project "artix-dc-scm"
				(path ""
					(reference "#PWR088")
					(unit 1)
				)
			)
		)
	)
	(symbol
		(lib_id "antmicroCapacitors0402:C_100n_0402")
		(at 154.94 31.75 90)
		(unit 1)
		(exclude_from_sim no)
		(in_bom yes)
		(on_board yes)
		(dnp no)
		(property "Reference" "C149"
			(at 155.575 27.305 90)
			(effects
				(font
					(size 1.27 1.27)
				)
				(justify right)
			)
		)
		(property "Value" "C_100n_0402"
			(at 165.1 11.43 0)
			(effects
				(font
					(size 1.27 1.27)
					(thickness 0.15)
				)
				(justify left bottom)
				(hide yes)
			)
		)
		(property "Footprint" "antmicro-footprints:C_0402_1005Metric"
			(at 167.64 11.43 0)
			(effects
				(font
					(size 1.27 1.27)
					(thickness 0.15)
				)
				(justify left bottom)
				(hide yes)
			)
		)
		(property "Datasheet" "https://www.murata.com/products/productdetail?partno=GRM155R61H104KE14%23"
			(at 170.18 11.43 0)
			(effects
				(font
					(size 1.27 1.27)
					(thickness 0.15)
				)
				(justify left bottom)
				(hide yes)
			)
		)
		(property "Description" "SMD Multilayer Ceramic Capacitor, 0.1 µF, 50 V, 0402 [1005 Metric], ± 10%, X5R, GRM Series"
			(at 154.94 31.75 0)
			(effects
				(font
					(size 1.27 1.27)
				)
				(hide yes)
			)
		)
		(property "Manufacturer" "Murata"
			(at 175.26 11.43 0)
			(effects
				(font
					(size 1.27 1.27)
					(thickness 0.15)
				)
				(justify left bottom)
				(hide yes)
			)
		)
		(property "MPN" "GRM155R61H104KE14D"
			(at 172.72 11.43 0)
			(effects
				(font
					(size 1.27 1.27)
					(thickness 0.15)
				)
				(justify left bottom)
				(hide yes)
			)
		)
		(property "Val" "100n"
			(at 155.575 31.115 90)
			(effects
				(font
					(size 1.27 1.27)
					(thickness 0.15)
				)
				(justify right)
			)
		)
		(property "License" "Apache-2.0"
			(at 177.8 11.43 0)
			(effects
				(font
					(size 1.27 1.27)
					(thickness 0.15)
				)
				(justify left bottom)
				(hide yes)
			)
		)
		(property "Author" "Antmicro"
			(at 180.34 11.43 0)
			(effects
				(font
					(size 1.27 1.27)
					(thickness 0.15)
				)
				(justify left bottom)
				(hide yes)
			)
		)
		(property "Voltage" "50V"
			(at 182.88 11.43 0)
			(effects
				(font
					(size 1.27 1.27)
				)
				(justify left bottom)
				(hide yes)
			)
		)
		(property "Dielectric" "X5R"
			(at 185.42 11.43 0)
			(effects
				(font
					(size 1.27 1.27)
				)
				(justify left bottom)
				(hide yes)
			)
		)
		(pin "1"
		)
		(pin "2"
		)
		(instances
			(project "artix-dc-scm"
				(path ""
					(reference "C149")
					(unit 1)
				)
			)
		)
	)
	(symbol
		(lib_id "antmicroCapacitors0402:C_100n_0402")
		(at 175.26 27.94 90)
		(unit 1)
		(exclude_from_sim no)
		(in_bom yes)
		(on_board yes)
		(dnp no)
		(fields_autoplaced yes)
		(property "Reference" "C139"
			(at 175.895 23.495 90)
			(effects
				(font
					(size 1.27 1.27)
				)
				(justify right)
			)
		)
		(property "Value" "C_100n_0402"
			(at 185.42 7.62 0)
			(effects
				(font
					(size 1.27 1.27)
					(thickness 0.15)
				)
				(justify left bottom)
				(hide yes)
			)
		)
		(property "Footprint" "antmicro-footprints:C_0402_1005Metric"
			(at 187.96 7.62 0)
			(effects
				(font
					(size 1.27 1.27)
					(thickness 0.15)
				)
				(justify left bottom)
				(hide yes)
			)
		)
		(property "Datasheet" "https://www.murata.com/products/productdetail?partno=GRM155R61H104KE14%23"
			(at 190.5 7.62 0)
			(effects
				(font
					(size 1.27 1.27)
					(thickness 0.15)
				)
				(justify left bottom)
				(hide yes)
			)
		)
		(property "Description" "SMD Multilayer Ceramic Capacitor, 0.1 µF, 50 V, 0402 [1005 Metric], ± 10%, X5R, GRM Series"
			(at 175.26 27.94 0)
			(effects
				(font
					(size 1.27 1.27)
				)
				(hide yes)
			)
		)
		(property "Manufacturer" "Murata"
			(at 195.58 7.62 0)
			(effects
				(font
					(size 1.27 1.27)
					(thickness 0.15)
				)
				(justify left bottom)
				(hide yes)
			)
		)
		(property "MPN" "GRM155R61H104KE14D"
			(at 193.04 7.62 0)
			(effects
				(font
					(size 1.27 1.27)
					(thickness 0.15)
				)
				(justify left bottom)
				(hide yes)
			)
		)
		(property "Val" "100n"
			(at 175.895 27.305 90)
			(effects
				(font
					(size 1.27 1.27)
					(thickness 0.15)
				)
				(justify right)
			)
		)
		(property "License" "Apache-2.0"
			(at 198.12 7.62 0)
			(effects
				(font
					(size 1.27 1.27)
					(thickness 0.15)
				)
				(justify left bottom)
				(hide yes)
			)
		)
		(property "Author" "Antmicro"
			(at 200.66 7.62 0)
			(effects
				(font
					(size 1.27 1.27)
					(thickness 0.15)
				)
				(justify left bottom)
				(hide yes)
			)
		)
		(property "Voltage" "50V"
			(at 203.2 7.62 0)
			(effects
				(font
					(size 1.27 1.27)
				)
				(justify left bottom)
				(hide yes)
			)
		)
		(property "Dielectric" "X5R"
			(at 205.74 7.62 0)
			(effects
				(font
					(size 1.27 1.27)
				)
				(justify left bottom)
				(hide yes)
			)
		)
		(pin "1"
		)
		(pin "2"
		)
		(instances
			(project "artix-dc-scm"
				(path ""
					(reference "C139")
					(unit 1)
				)
			)
		)
	)
	(symbol
		(lib_id "antmicroCapacitors0402:C_4u7_0402")
		(at 147.32 31.75 90)
		(unit 1)
		(exclude_from_sim no)
		(in_bom yes)
		(on_board yes)
		(dnp no)
		(property "Reference" "C154"
			(at 147.955 27.305 90)
			(effects
				(font
					(size 1.27 1.27)
				)
				(justify right)
			)
		)
		(property "Value" "C_4u7_0402"
			(at 157.48 11.43 0)
			(effects
				(font
					(size 1.27 1.27)
					(thickness 0.15)
				)
				(justify left bottom)
				(hide yes)
			)
		)
		(property "Footprint" "antmicro-footprints:C_0402_1005Metric"
			(at 160.02 11.43 0)
			(effects
				(font
					(size 1.27 1.27)
					(thickness 0.15)
				)
				(justify left bottom)
				(hide yes)
			)
		)
		(property "Datasheet" "https://www.murata.com/products/productdetail?partno=GRM155R61A475MEAA%23"
			(at 162.56 11.43 0)
			(effects
				(font
					(size 1.27 1.27)
					(thickness 0.15)
				)
				(justify left bottom)
				(hide yes)
			)
		)
		(property "Description" "SMD Multilayer Ceramic Capacitor, 4.7 µF, 10 V, 0402 [1005 Metric], ± 20%, X5R, GRM Series"
			(at 147.32 31.75 0)
			(effects
				(font
					(size 1.27 1.27)
				)
				(hide yes)
			)
		)
		(property "Manufacturer" "Murata"
			(at 167.64 11.43 0)
			(effects
				(font
					(size 1.27 1.27)
					(thickness 0.15)
				)
				(justify left bottom)
				(hide yes)
			)
		)
		(property "MPN" "GRM155R61A475MEAAD"
			(at 165.1 11.43 0)
			(effects
				(font
					(size 1.27 1.27)
					(thickness 0.15)
				)
				(justify left bottom)
				(hide yes)
			)
		)
		(property "Val" "4u7"
			(at 147.955 31.115 90)
			(effects
				(font
					(size 1.27 1.27)
					(thickness 0.15)
				)
				(justify right)
			)
		)
		(property "License" "Apache-2.0"
			(at 170.18 11.43 0)
			(effects
				(font
					(size 1.27 1.27)
					(thickness 0.15)
				)
				(justify left bottom)
				(hide yes)
			)
		)
		(property "Author" "Antmicro"
			(at 172.72 11.43 0)
			(effects
				(font
					(size 1.27 1.27)
					(thickness 0.15)
				)
				(justify left bottom)
				(hide yes)
			)
		)
		(property "Voltage" ""
			(at 175.26 11.43 0)
			(effects
				(font
					(size 1.27 1.27)
				)
				(justify left bottom)
				(hide yes)
			)
		)
		(property "Dielectric" ""
			(at 177.8 11.43 0)
			(effects
				(font
					(size 1.27 1.27)
				)
				(justify left bottom)
				(hide yes)
			)
		)
		(pin "1"
		)
		(pin "2"
		)
		(instances
			(project "artix-dc-scm"
				(path ""
					(reference "C154")
					(unit 1)
				)
			)
		)
	)
	(symbol
		(lib_id "antmicropower:GND")
		(at 121.92 179.07 0)
		(unit 1)
		(exclude_from_sim no)
		(in_bom yes)
		(on_board yes)
		(dnp no)
		(property "Reference" "#PWR0128"
			(at 121.92 185.42 0)
			(effects
				(font
					(size 1.27 1.27)
				)
				(hide yes)
			)
		)
		(property "Value" "GND"
			(at 121.92 182.88 0)
			(effects
				(font
					(size 1.27 1.27)
				)
			)
		)
		(property "Footprint" ""
			(at 121.92 179.07 0)
			(effects
				(font
					(size 1.27 1.27)
				)
				(hide yes)
			)
		)
		(property "Datasheet" ""
			(at 121.92 179.07 0)
			(effects
				(font
					(size 1.27 1.27)
				)
				(hide yes)
			)
		)
		(property "Description" ""
			(at 121.92 179.07 0)
			(effects
				(font
					(size 1.27 1.27)
				)
				(hide yes)
			)
		)
		(property "Author" "Antmicro"
			(at 130.81 186.69 0)
			(effects
				(font
					(size 1.27 1.27)
					(thickness 0.15)
				)
				(justify left bottom)
				(hide yes)
			)
		)
		(property "License" "Apache-2.0"
			(at 130.81 189.23 0)
			(effects
				(font
					(size 1.27 1.27)
					(thickness 0.15)
				)
				(justify left bottom)
				(hide yes)
			)
		)
		(pin "1"
		)
		(instances
			(project "artix-dc-scm"
				(path ""
					(reference "#PWR0128")
					(unit 1)
				)
			)
		)
	)
	(symbol
		(lib_id "antmicroCapacitorsmisc:C_100n_6V3_0402")
		(at 121.92 179.07 270)
		(mirror x)
		(unit 1)
		(exclude_from_sim no)
		(in_bom yes)
		(on_board yes)
		(dnp no)
		(property "Reference" "C17"
			(at 122.555 174.625 90)
			(effects
				(font
					(size 1.27 1.27)
				)
				(justify left)
			)
		)
		(property "Value" "C_100n_6V3_0402"
			(at 111.76 158.75 0)
			(effects
				(font
					(size 1.27 1.27)
					(thickness 0.15)
				)
				(justify left bottom)
				(hide yes)
			)
		)
		(property "Footprint" "antmicro-footprints:C_0402_1005Metric"
			(at 109.22 158.75 0)
			(effects
				(font
					(size 1.27 1.27)
					(thickness 0.15)
				)
				(justify left bottom)
				(hide yes)
			)
		)
		(property "Datasheet" "https://www.passivecomponent.com/wp-content/uploads/datasheet/WTC_MLCC_General_Purpose.pdf"
			(at 106.68 158.75 0)
			(effects
				(font
					(size 1.27 1.27)
					(thickness 0.15)
				)
				(justify left bottom)
				(hide yes)
			)
		)
		(property "Description" "SMT Multilayer Ceramic Capacitor, 0.1 µF, 6.3 V, 0402 [1005 Metric], ± 10%, X5R, Walsin MLCC"
			(at 121.92 179.07 0)
			(effects
				(font
					(size 1.27 1.27)
				)
				(hide yes)
			)
		)
		(property "Manufacturer" "Walsin"
			(at 101.6 158.75 0)
			(effects
				(font
					(size 1.27 1.27)
					(thickness 0.15)
				)
				(justify left bottom)
				(hide yes)
			)
		)
		(property "MPN" "0402X104K6R3CT"
			(at 104.14 158.75 0)
			(effects
				(font
					(size 1.27 1.27)
					(thickness 0.15)
				)
				(justify left bottom)
				(hide yes)
			)
		)
		(property "Val" "100n"
			(at 122.555 178.435 90)
			(effects
				(font
					(size 1.27 1.27)
					(thickness 0.15)
				)
				(justify left)
			)
		)
		(property "License" "Apache-2.0"
			(at 99.06 158.75 0)
			(effects
				(font
					(size 1.27 1.27)
					(thickness 0.15)
				)
				(justify left bottom)
				(hide yes)
			)
		)
		(property "Author" "Antmicro"
			(at 96.52 158.75 0)
			(effects
				(font
					(size 1.27 1.27)
					(thickness 0.15)
				)
				(justify left bottom)
				(hide yes)
			)
		)
		(property "Voltage" ""
			(at 93.98 158.75 0)
			(effects
				(font
					(size 1.27 1.27)
				)
				(justify left bottom)
				(hide yes)
			)
		)
		(property "Dielectric" ""
			(at 91.44 158.75 0)
			(effects
				(font
					(size 1.27 1.27)
				)
				(justify left bottom)
				(hide yes)
			)
		)
		(property "Public" "False"
			(at 88.9 158.75 0)
			(effects
				(font
					(size 1.27 1.27)
				)
				(justify left bottom)
				(hide yes)
			)
		)
		(pin "1"
		)
		(pin "2"
		)
		(instances
			(project "artix-dc-scm"
				(path ""
					(reference "C17")
					(unit 1)
				)
			)
		)
	)
	(symbol
		(lib_id "antmicropower:GND")
		(at 393.7 30.48 0)
		(unit 1)
		(exclude_from_sim no)
		(in_bom yes)
		(on_board yes)
		(dnp no)
		(property "Reference" "#PWR0152"
			(at 393.7 36.83 0)
			(effects
				(font
					(size 1.27 1.27)
				)
				(hide yes)
			)
		)
		(property "Value" "GND"
			(at 393.7 34.29 0)
			(effects
				(font
					(size 1.27 1.27)
				)
			)
		)
		(property "Footprint" ""
			(at 393.7 30.48 0)
			(effects
				(font
					(size 1.27 1.27)
				)
				(hide yes)
			)
		)
		(property "Datasheet" ""
			(at 393.7 30.48 0)
			(effects
				(font
					(size 1.27 1.27)
				)
				(hide yes)
			)
		)
		(property "Description" ""
			(at 393.7 30.48 0)
			(effects
				(font
					(size 1.27 1.27)
				)
				(hide yes)
			)
		)
		(property "Author" "Antmicro"
			(at 402.59 38.1 0)
			(effects
				(font
					(size 1.27 1.27)
					(thickness 0.15)
				)
				(justify left bottom)
				(hide yes)
			)
		)
		(property "License" "Apache-2.0"
			(at 402.59 40.64 0)
			(effects
				(font
					(size 1.27 1.27)
					(thickness 0.15)
				)
				(justify left bottom)
				(hide yes)
			)
		)
		(pin "1"
		)
		(instances
			(project "artix-dc-scm"
				(path ""
					(reference "#PWR0152")
					(unit 1)
				)
			)
		)
	)
	(symbol
		(lib_id "antmicropower:GND")
		(at 393.7 44.45 0)
		(unit 1)
		(exclude_from_sim no)
		(in_bom yes)
		(on_board yes)
		(dnp no)
		(property "Reference" "#PWR0114"
			(at 393.7 50.8 0)
			(effects
				(font
					(size 1.27 1.27)
				)
				(hide yes)
			)
		)
		(property "Value" "GND"
			(at 393.7 48.26 0)
			(effects
				(font
					(size 1.27 1.27)
				)
			)
		)
		(property "Footprint" ""
			(at 393.7 44.45 0)
			(effects
				(font
					(size 1.27 1.27)
				)
				(hide yes)
			)
		)
		(property "Datasheet" ""
			(at 393.7 44.45 0)
			(effects
				(font
					(size 1.27 1.27)
				)
				(hide yes)
			)
		)
		(property "Description" ""
			(at 393.7 44.45 0)
			(effects
				(font
					(size 1.27 1.27)
				)
				(hide yes)
			)
		)
		(property "Author" "Antmicro"
			(at 402.59 52.07 0)
			(effects
				(font
					(size 1.27 1.27)
					(thickness 0.15)
				)
				(justify left bottom)
				(hide yes)
			)
		)
		(property "License" "Apache-2.0"
			(at 402.59 54.61 0)
			(effects
				(font
					(size 1.27 1.27)
					(thickness 0.15)
				)
				(justify left bottom)
				(hide yes)
			)
		)
		(pin "1"
		)
		(instances
			(project "artix-dc-scm"
				(path ""
					(reference "#PWR0114")
					(unit 1)
				)
			)
		)
	)
	(symbol
		(lib_id "antmicroCapacitors0402:C_4u7_0402")
		(at 400.05 30.48 90)
		(unit 1)
		(exclude_from_sim no)
		(in_bom yes)
		(on_board yes)
		(dnp no)
		(property "Reference" "C247"
			(at 400.685 26.035 90)
			(effects
				(font
					(size 1.27 1.27)
				)
				(justify right)
			)
		)
		(property "Value" "C_4u7_0402"
			(at 410.21 10.16 0)
			(effects
				(font
					(size 1.27 1.27)
					(thickness 0.15)
				)
				(justify left bottom)
				(hide yes)
			)
		)
		(property "Footprint" "antmicro-footprints:C_0402_1005Metric"
			(at 412.75 10.16 0)
			(effects
				(font
					(size 1.27 1.27)
					(thickness 0.15)
				)
				(justify left bottom)
				(hide yes)
			)
		)
		(property "Datasheet" "https://www.murata.com/products/productdetail?partno=GRM155R61A475MEAA%23"
			(at 415.29 10.16 0)
			(effects
				(font
					(size 1.27 1.27)
					(thickness 0.15)
				)
				(justify left bottom)
				(hide yes)
			)
		)
		(property "Description" "SMD Multilayer Ceramic Capacitor, 4.7 µF, 10 V, 0402 [1005 Metric], ± 20%, X5R, GRM Series"
			(at 400.05 30.48 0)
			(effects
				(font
					(size 1.27 1.27)
				)
				(hide yes)
			)
		)
		(property "Manufacturer" "Murata"
			(at 420.37 10.16 0)
			(effects
				(font
					(size 1.27 1.27)
					(thickness 0.15)
				)
				(justify left bottom)
				(hide yes)
			)
		)
		(property "MPN" "GRM155R61A475MEAAD"
			(at 417.83 10.16 0)
			(effects
				(font
					(size 1.27 1.27)
					(thickness 0.15)
				)
				(justify left bottom)
				(hide yes)
			)
		)
		(property "Val" "4u7"
			(at 400.685 29.845 90)
			(effects
				(font
					(size 1.27 1.27)
					(thickness 0.15)
				)
				(justify right)
			)
		)
		(property "License" "Apache-2.0"
			(at 422.91 10.16 0)
			(effects
				(font
					(size 1.27 1.27)
					(thickness 0.15)
				)
				(justify left bottom)
				(hide yes)
			)
		)
		(property "Author" "Antmicro"
			(at 425.45 10.16 0)
			(effects
				(font
					(size 1.27 1.27)
					(thickness 0.15)
				)
				(justify left bottom)
				(hide yes)
			)
		)
		(property "Voltage" ""
			(at 427.99 10.16 0)
			(effects
				(font
					(size 1.27 1.27)
				)
				(justify left bottom)
				(hide yes)
			)
		)
		(property "Dielectric" ""
			(at 430.53 10.16 0)
			(effects
				(font
					(size 1.27 1.27)
				)
				(justify left bottom)
				(hide yes)
			)
		)
		(pin "1"
		)
		(pin "2"
		)
		(instances
			(project "artix-dc-scm"
				(path ""
					(reference "C247")
					(unit 1)
				)
			)
		)
	)
	(symbol
		(lib_id "antmicroCapacitors0402:C_4u7_0402")
		(at 400.05 44.45 90)
		(unit 1)
		(exclude_from_sim no)
		(in_bom yes)
		(on_board yes)
		(dnp no)
		(property "Reference" "C246"
			(at 400.685 40.005 90)
			(effects
				(font
					(size 1.27 1.27)
				)
				(justify right)
			)
		)
		(property "Value" "C_4u7_0402"
			(at 410.21 24.13 0)
			(effects
				(font
					(size 1.27 1.27)
					(thickness 0.15)
				)
				(justify left bottom)
				(hide yes)
			)
		)
		(property "Footprint" "antmicro-footprints:C_0402_1005Metric"
			(at 412.75 24.13 0)
			(effects
				(font
					(size 1.27 1.27)
					(thickness 0.15)
				)
				(justify left bottom)
				(hide yes)
			)
		)
		(property "Datasheet" "https://www.murata.com/products/productdetail?partno=GRM155R61A475MEAA%23"
			(at 415.29 24.13 0)
			(effects
				(font
					(size 1.27 1.27)
					(thickness 0.15)
				)
				(justify left bottom)
				(hide yes)
			)
		)
		(property "Description" "SMD Multilayer Ceramic Capacitor, 4.7 µF, 10 V, 0402 [1005 Metric], ± 20%, X5R, GRM Series"
			(at 400.05 44.45 0)
			(effects
				(font
					(size 1.27 1.27)
				)
				(hide yes)
			)
		)
		(property "Manufacturer" "Murata"
			(at 420.37 24.13 0)
			(effects
				(font
					(size 1.27 1.27)
					(thickness 0.15)
				)
				(justify left bottom)
				(hide yes)
			)
		)
		(property "MPN" "GRM155R61A475MEAAD"
			(at 417.83 24.13 0)
			(effects
				(font
					(size 1.27 1.27)
					(thickness 0.15)
				)
				(justify left bottom)
				(hide yes)
			)
		)
		(property "Val" "4u7"
			(at 400.685 43.815 90)
			(effects
				(font
					(size 1.27 1.27)
					(thickness 0.15)
				)
				(justify right)
			)
		)
		(property "License" "Apache-2.0"
			(at 422.91 24.13 0)
			(effects
				(font
					(size 1.27 1.27)
					(thickness 0.15)
				)
				(justify left bottom)
				(hide yes)
			)
		)
		(property "Author" "Antmicro"
			(at 425.45 24.13 0)
			(effects
				(font
					(size 1.27 1.27)
					(thickness 0.15)
				)
				(justify left bottom)
				(hide yes)
			)
		)
		(property "Voltage" ""
			(at 427.99 24.13 0)
			(effects
				(font
					(size 1.27 1.27)
				)
				(justify left bottom)
				(hide yes)
			)
		)
		(property "Dielectric" ""
			(at 430.53 24.13 0)
			(effects
				(font
					(size 1.27 1.27)
				)
				(justify left bottom)
				(hide yes)
			)
		)
		(pin "1"
		)
		(pin "2"
		)
		(instances
			(project "artix-dc-scm"
				(path ""
					(reference "C246")
					(unit 1)
				)
			)
		)
	)
	(symbol
		(lib_id "antmicropower:GND")
		(at 400.05 44.45 0)
		(unit 1)
		(exclude_from_sim no)
		(in_bom yes)
		(on_board yes)
		(dnp no)
		(property "Reference" "#PWR0153"
			(at 400.05 50.8 0)
			(effects
				(font
					(size 1.27 1.27)
				)
				(hide yes)
			)
		)
		(property "Value" "GND"
			(at 400.05 48.26 0)
			(effects
				(font
					(size 1.27 1.27)
				)
			)
		)
		(property "Footprint" ""
			(at 400.05 44.45 0)
			(effects
				(font
					(size 1.27 1.27)
				)
				(hide yes)
			)
		)
		(property "Datasheet" ""
			(at 400.05 44.45 0)
			(effects
				(font
					(size 1.27 1.27)
				)
				(hide yes)
			)
		)
		(property "Description" ""
			(at 400.05 44.45 0)
			(effects
				(font
					(size 1.27 1.27)
				)
				(hide yes)
			)
		)
		(property "Author" "Antmicro"
			(at 408.94 52.07 0)
			(effects
				(font
					(size 1.27 1.27)
					(thickness 0.15)
				)
				(justify left bottom)
				(hide yes)
			)
		)
		(property "License" "Apache-2.0"
			(at 408.94 54.61 0)
			(effects
				(font
					(size 1.27 1.27)
					(thickness 0.15)
				)
				(justify left bottom)
				(hide yes)
			)
		)
		(pin "1"
		)
		(instances
			(project "artix-dc-scm"
				(path ""
					(reference "#PWR0153")
					(unit 1)
				)
			)
		)
	)
	(symbol
		(lib_id "antmicropower:GND")
		(at 400.05 30.48 0)
		(unit 1)
		(exclude_from_sim no)
		(in_bom yes)
		(on_board yes)
		(dnp no)
		(property "Reference" "#PWR0154"
			(at 400.05 36.83 0)
			(effects
				(font
					(size 1.27 1.27)
				)
				(hide yes)
			)
		)
		(property "Value" "GND"
			(at 400.05 34.29 0)
			(effects
				(font
					(size 1.27 1.27)
				)
			)
		)
		(property "Footprint" ""
			(at 400.05 30.48 0)
			(effects
				(font
					(size 1.27 1.27)
				)
				(hide yes)
			)
		)
		(property "Datasheet" ""
			(at 400.05 30.48 0)
			(effects
				(font
					(size 1.27 1.27)
				)
				(hide yes)
			)
		)
		(property "Description" ""
			(at 400.05 30.48 0)
			(effects
				(font
					(size 1.27 1.27)
				)
				(hide yes)
			)
		)
		(property "Author" "Antmicro"
			(at 408.94 38.1 0)
			(effects
				(font
					(size 1.27 1.27)
					(thickness 0.15)
				)
				(justify left bottom)
				(hide yes)
			)
		)
		(property "License" "Apache-2.0"
			(at 408.94 40.64 0)
			(effects
				(font
					(size 1.27 1.27)
					(thickness 0.15)
				)
				(justify left bottom)
				(hide yes)
			)
		)
		(pin "1"
		)
		(instances
			(project "artix-dc-scm"
				(path ""
					(reference "#PWR0154")
					(unit 1)
				)
			)
		)
	)
	(symbol
		(lib_id "antmicroCapacitors0402:C_4u7_0402")
		(at 167.64 27.94 90)
		(unit 1)
		(exclude_from_sim no)
		(in_bom yes)
		(on_board yes)
		(dnp no)
		(fields_autoplaced yes)
		(property "Reference" "C162"
			(at 168.275 23.495 90)
			(effects
				(font
					(size 1.27 1.27)
				)
				(justify right)
			)
		)
		(property "Value" "C_4u7_0402"
			(at 177.8 7.62 0)
			(effects
				(font
					(size 1.27 1.27)
					(thickness 0.15)
				)
				(justify left bottom)
				(hide yes)
			)
		)
		(property "Footprint" "antmicro-footprints:C_0402_1005Metric"
			(at 180.34 7.62 0)
			(effects
				(font
					(size 1.27 1.27)
					(thickness 0.15)
				)
				(justify left bottom)
				(hide yes)
			)
		)
		(property "Datasheet" "https://www.murata.com/products/productdetail?partno=GRM155R61A475MEAA%23"
			(at 182.88 7.62 0)
			(effects
				(font
					(size 1.27 1.27)
					(thickness 0.15)
				)
				(justify left bottom)
				(hide yes)
			)
		)
		(property "Description" "SMD Multilayer Ceramic Capacitor, 4.7 µF, 10 V, 0402 [1005 Metric], ± 20%, X5R, GRM Series"
			(at 167.64 27.94 0)
			(effects
				(font
					(size 1.27 1.27)
				)
				(hide yes)
			)
		)
		(property "Manufacturer" "Murata"
			(at 187.96 7.62 0)
			(effects
				(font
					(size 1.27 1.27)
					(thickness 0.15)
				)
				(justify left bottom)
				(hide yes)
			)
		)
		(property "MPN" "GRM155R61A475MEAAD"
			(at 185.42 7.62 0)
			(effects
				(font
					(size 1.27 1.27)
					(thickness 0.15)
				)
				(justify left bottom)
				(hide yes)
			)
		)
		(property "Val" "4u7"
			(at 168.275 27.305 90)
			(effects
				(font
					(size 1.27 1.27)
					(thickness 0.15)
				)
				(justify right)
			)
		)
		(property "License" "Apache-2.0"
			(at 190.5 7.62 0)
			(effects
				(font
					(size 1.27 1.27)
					(thickness 0.15)
				)
				(justify left bottom)
				(hide yes)
			)
		)
		(property "Author" "Antmicro"
			(at 193.04 7.62 0)
			(effects
				(font
					(size 1.27 1.27)
					(thickness 0.15)
				)
				(justify left bottom)
				(hide yes)
			)
		)
		(property "Voltage" ""
			(at 195.58 7.62 0)
			(effects
				(font
					(size 1.27 1.27)
				)
				(justify left bottom)
				(hide yes)
			)
		)
		(property "Dielectric" ""
			(at 198.12 7.62 0)
			(effects
				(font
					(size 1.27 1.27)
				)
				(justify left bottom)
				(hide yes)
			)
		)
		(pin "1"
		)
		(pin "2"
		)
		(instances
			(project "artix-dc-scm"
				(path ""
					(reference "C162")
					(unit 1)
				)
			)
		)
	)
	(symbol
		(lib_id "antmicropower:GND")
		(at 147.32 31.75 0)
		(unit 1)
		(exclude_from_sim no)
		(in_bom yes)
		(on_board yes)
		(dnp no)
		(property "Reference" "#PWR0136"
			(at 147.32 38.1 0)
			(effects
				(font
					(size 1.27 1.27)
				)
				(hide yes)
			)
		)
		(property "Value" "GND"
			(at 147.32 35.56 0)
			(effects
				(font
					(size 1.27 1.27)
				)
			)
		)
		(property "Footprint" ""
			(at 147.32 31.75 0)
			(effects
				(font
					(size 1.27 1.27)
				)
				(hide yes)
			)
		)
		(property "Datasheet" ""
			(at 147.32 31.75 0)
			(effects
				(font
					(size 1.27 1.27)
				)
				(hide yes)
			)
		)
		(property "Description" ""
			(at 147.32 31.75 0)
			(effects
				(font
					(size 1.27 1.27)
				)
				(hide yes)
			)
		)
		(property "Author" "Antmicro"
			(at 156.21 39.37 0)
			(effects
				(font
					(size 1.27 1.27)
					(thickness 0.15)
				)
				(justify left bottom)
				(hide yes)
			)
		)
		(property "License" "Apache-2.0"
			(at 156.21 41.91 0)
			(effects
				(font
					(size 1.27 1.27)
					(thickness 0.15)
				)
				(justify left bottom)
				(hide yes)
			)
		)
		(pin "1"
		)
		(instances
			(project "artix-dc-scm"
				(path ""
					(reference "#PWR0136")
					(unit 1)
				)
			)
		)
	)
	(symbol
		(lib_id "antmicropower:GND")
		(at 154.94 31.75 0)
		(unit 1)
		(exclude_from_sim no)
		(in_bom yes)
		(on_board yes)
		(dnp no)
		(property "Reference" "#PWR0137"
			(at 154.94 38.1 0)
			(effects
				(font
					(size 1.27 1.27)
				)
				(hide yes)
			)
		)
		(property "Value" "GND"
			(at 154.94 35.56 0)
			(effects
				(font
					(size 1.27 1.27)
				)
			)
		)
		(property "Footprint" ""
			(at 154.94 31.75 0)
			(effects
				(font
					(size 1.27 1.27)
				)
				(hide yes)
			)
		)
		(property "Datasheet" ""
			(at 154.94 31.75 0)
			(effects
				(font
					(size 1.27 1.27)
				)
				(hide yes)
			)
		)
		(property "Description" ""
			(at 154.94 31.75 0)
			(effects
				(font
					(size 1.27 1.27)
				)
				(hide yes)
			)
		)
		(property "Author" "Antmicro"
			(at 163.83 39.37 0)
			(effects
				(font
					(size 1.27 1.27)
					(thickness 0.15)
				)
				(justify left bottom)
				(hide yes)
			)
		)
		(property "License" "Apache-2.0"
			(at 163.83 41.91 0)
			(effects
				(font
					(size 1.27 1.27)
					(thickness 0.15)
				)
				(justify left bottom)
				(hide yes)
			)
		)
		(pin "1"
		)
		(instances
			(project "artix-dc-scm"
				(path ""
					(reference "#PWR0137")
					(unit 1)
				)
			)
		)
	)
	(symbol
		(lib_id "antmicropower:GND")
		(at 167.64 27.94 0)
		(unit 1)
		(exclude_from_sim no)
		(in_bom yes)
		(on_board yes)
		(dnp no)
		(property "Reference" "#PWR0135"
			(at 167.64 34.29 0)
			(effects
				(font
					(size 1.27 1.27)
				)
				(hide yes)
			)
		)
		(property "Value" "GND"
			(at 167.64 31.75 0)
			(effects
				(font
					(size 1.27 1.27)
				)
			)
		)
		(property "Footprint" ""
			(at 167.64 27.94 0)
			(effects
				(font
					(size 1.27 1.27)
				)
				(hide yes)
			)
		)
		(property "Datasheet" ""
			(at 167.64 27.94 0)
			(effects
				(font
					(size 1.27 1.27)
				)
				(hide yes)
			)
		)
		(property "Description" ""
			(at 167.64 27.94 0)
			(effects
				(font
					(size 1.27 1.27)
				)
				(hide yes)
			)
		)
		(property "Author" "Antmicro"
			(at 176.53 35.56 0)
			(effects
				(font
					(size 1.27 1.27)
					(thickness 0.15)
				)
				(justify left bottom)
				(hide yes)
			)
		)
		(property "License" "Apache-2.0"
			(at 176.53 38.1 0)
			(effects
				(font
					(size 1.27 1.27)
					(thickness 0.15)
				)
				(justify left bottom)
				(hide yes)
			)
		)
		(pin "1"
		)
		(instances
			(project "artix-dc-scm"
				(path ""
					(reference "#PWR0135")
					(unit 1)
				)
			)
		)
	)
	(symbol
		(lib_id "antmicropower:GND")
		(at 175.26 27.94 0)
		(unit 1)
		(exclude_from_sim no)
		(in_bom yes)
		(on_board yes)
		(dnp no)
		(fields_autoplaced yes)
		(property "Reference" "#PWR0138"
			(at 175.26 34.29 0)
			(effects
				(font
					(size 1.27 1.27)
				)
				(hide yes)
			)
		)
		(property "Value" "GND"
			(at 175.26 31.75 0)
			(effects
				(font
					(size 1.27 1.27)
				)
			)
		)
		(property "Footprint" ""
			(at 175.26 27.94 0)
			(effects
				(font
					(size 1.27 1.27)
				)
				(hide yes)
			)
		)
		(property "Datasheet" ""
			(at 175.26 27.94 0)
			(effects
				(font
					(size 1.27 1.27)
				)
				(hide yes)
			)
		)
		(property "Description" ""
			(at 175.26 27.94 0)
			(effects
				(font
					(size 1.27 1.27)
				)
				(hide yes)
			)
		)
		(property "Author" "Antmicro"
			(at 184.15 35.56 0)
			(effects
				(font
					(size 1.27 1.27)
					(thickness 0.15)
				)
				(justify left bottom)
				(hide yes)
			)
		)
		(property "License" "Apache-2.0"
			(at 184.15 38.1 0)
			(effects
				(font
					(size 1.27 1.27)
					(thickness 0.15)
				)
				(justify left bottom)
				(hide yes)
			)
		)
		(pin "1"
		)
		(instances
			(project "artix-dc-scm"
				(path ""
					(reference "#PWR0138")
					(unit 1)
				)
			)
		)
	)
	(symbol
		(lib_id "antmicropower:GND")
		(at 134.62 99.06 0)
		(unit 1)
		(exclude_from_sim no)
		(in_bom yes)
		(on_board yes)
		(dnp no)
		(property "Reference" "#PWR0129"
			(at 134.62 105.41 0)
			(effects
				(font
					(size 1.27 1.27)
				)
				(hide yes)
			)
		)
		(property "Value" "GND"
			(at 134.62 102.87 0)
			(effects
				(font
					(size 1.27 1.27)
				)
			)
		)
		(property "Footprint" ""
			(at 134.62 99.06 0)
			(effects
				(font
					(size 1.27 1.27)
				)
				(hide yes)
			)
		)
		(property "Datasheet" ""
			(at 134.62 99.06 0)
			(effects
				(font
					(size 1.27 1.27)
				)
				(hide yes)
			)
		)
		(property "Description" ""
			(at 134.62 99.06 0)
			(effects
				(font
					(size 1.27 1.27)
				)
				(hide yes)
			)
		)
		(property "Author" "Antmicro"
			(at 143.51 106.68 0)
			(effects
				(font
					(size 1.27 1.27)
					(thickness 0.15)
				)
				(justify left bottom)
				(hide yes)
			)
		)
		(property "License" "Apache-2.0"
			(at 143.51 109.22 0)
			(effects
				(font
					(size 1.27 1.27)
					(thickness 0.15)
				)
				(justify left bottom)
				(hide yes)
			)
		)
		(pin "1"
		)
		(instances
			(project "artix-dc-scm"
				(path ""
					(reference "#PWR0129")
					(unit 1)
				)
			)
		)
	)
	(symbol
		(lib_id "antmicroTVSDiodes:TPD2E009_SOT-9X3")
		(at 153.67 88.9 270)
		(unit 1)
		(exclude_from_sim no)
		(in_bom yes)
		(on_board yes)
		(dnp no)
		(fields_autoplaced yes)
		(property "Reference" "D15"
			(at 151.13 100.33 90)
			(effects
				(font
					(size 1.27 1.27)
				)
			)
		)
		(property "Value" "TPD2E009_SOT-9X3"
			(at 151.13 102.87 90)
			(effects
				(font
					(size 1.27 1.27)
					(thickness 0.15)
				)
			)
		)
		(property "Footprint" "antmicro-footprints:SOT-723"
			(at 148.59 104.14 0)
			(effects
				(font
					(size 1.27 1.27)
					(thickness 0.15)
				)
				(justify left bottom)
				(hide yes)
			)
		)
		(property "Datasheet" "https://www.ti.com/lit/ds/symlink/tpd2e009.pdf?ts=1597910439511&ref_url=https%253A%252F%252Fwww.google.com%252F"
			(at 146.05 104.14 0)
			(effects
				(font
					(size 1.27 1.27)
					(thickness 0.15)
				)
				(justify left bottom)
				(hide yes)
			)
		)
		(property "Description" "TVS diode array, 8 kV, SOT-723, 5.5 V, 0.9 pF"
			(at 153.67 88.9 0)
			(effects
				(font
					(size 1.27 1.27)
				)
				(hide yes)
			)
		)
		(property "MPN" "TPD2E009DRTR"
			(at 143.51 104.14 0)
			(effects
				(font
					(size 1.27 1.27)
					(thickness 0.15)
				)
				(justify left bottom)
				(hide yes)
			)
		)
		(property "Manufacturer" "Texas Instruments"
			(at 140.97 104.14 0)
			(effects
				(font
					(size 1.27 1.27)
					(thickness 0.15)
				)
				(justify left bottom)
				(hide yes)
			)
		)
		(property "Author" "Antmicro"
			(at 138.43 104.14 0)
			(effects
				(font
					(size 1.27 1.27)
					(thickness 0.15)
				)
				(justify left bottom)
				(hide yes)
			)
		)
		(property "License" "Apache-2.0"
			(at 135.89 104.14 0)
			(effects
				(font
					(size 1.27 1.27)
					(thickness 0.15)
				)
				(justify left bottom)
				(hide yes)
			)
		)
		(pin "1"
		)
		(pin "2"
		)
		(pin "3"
		)
		(instances
			(project "artix-dc-scm"
				(path ""
					(reference "D15")
					(unit 1)
				)
			)
		)
	)
	(symbol
		(lib_id "antmicroResistors0402:R_12k1_0402")
		(at 175.26 132.08 90)
		(unit 1)
		(exclude_from_sim no)
		(in_bom yes)
		(on_board yes)
		(dnp no)
		(property "Reference" "R3"
			(at 176.53 128.27 90)
			(effects
				(font
					(size 1.27 1.27)
				)
				(justify right)
			)
		)
		(property "Value" "R_12k1_0402"
			(at 187.96 111.76 0)
			(effects
				(font
					(size 1.27 1.27)
					(thickness 0.15)
				)
				(justify left bottom)
				(hide yes)
			)
		)
		(property "Footprint" "antmicro-footprints:R_0402_1005Metric"
			(at 190.5 111.76 0)
			(effects
				(font
					(size 1.27 1.27)
					(thickness 0.15)
				)
				(justify left bottom)
				(hide yes)
			)
		)
		(property "Datasheet" "https://www.bourns.com/docs/product-datasheets/cr.pdf"
			(at 193.04 111.76 0)
			(effects
				(font
					(size 1.27 1.27)
					(thickness 0.15)
				)
				(justify left bottom)
				(hide yes)
			)
		)
		(property "Description" "SMD Chip Resistor, 12.1 kohm, ± 1%, 62.5 mW, 0402 [1005 Metric], Thick Film, General Purpose"
			(at 175.26 132.08 0)
			(effects
				(font
					(size 1.27 1.27)
				)
				(hide yes)
			)
		)
		(property "Manufacturer" "Bourns"
			(at 198.12 111.76 0)
			(effects
				(font
					(size 1.27 1.27)
					(thickness 0.15)
				)
				(justify left bottom)
				(hide yes)
			)
		)
		(property "MPN" "CR0402-FX-1212GLF"
			(at 195.58 111.76 0)
			(effects
				(font
					(size 1.27 1.27)
					(thickness 0.15)
				)
				(justify left bottom)
				(hide yes)
			)
		)
		(property "Val" "12k1"
			(at 176.53 130.81 90)
			(effects
				(font
					(size 1.27 1.27)
					(thickness 0.15)
				)
				(justify right)
			)
		)
		(property "License" "Apache-2.0"
			(at 200.66 111.76 0)
			(effects
				(font
					(size 1.27 1.27)
					(thickness 0.15)
				)
				(justify left bottom)
				(hide yes)
			)
		)
		(property "Author" "Antmicro"
			(at 203.2 111.76 0)
			(effects
				(font
					(size 1.27 1.27)
					(thickness 0.15)
				)
				(justify left bottom)
				(hide yes)
			)
		)
		(property "Tolerance" "1%"
			(at 185.42 111.76 0)
			(effects
				(font
					(size 1.27 1.27)
				)
				(justify left bottom)
				(hide yes)
			)
		)
		(pin "1"
		)
		(pin "2"
		)
		(instances
			(project "artix-dc-scm"
				(path ""
					(reference "R3")
					(unit 1)
				)
			)
		)
	)
	(symbol
		(lib_id "antmicroResistors0402:R_10k_0402")
		(at 175.26 96.52 270)
		(unit 1)
		(exclude_from_sim no)
		(in_bom yes)
		(on_board yes)
		(dnp no)
		(property "Reference" "R4"
			(at 176.53 97.79 90)
			(effects
				(font
					(size 1.27 1.27)
				)
				(justify left)
			)
		)
		(property "Value" "R_10k_0402"
			(at 162.56 116.84 0)
			(effects
				(font
					(size 1.27 1.27)
					(thickness 0.15)
				)
				(justify left bottom)
				(hide yes)
			)
		)
		(property "Footprint" "antmicro-footprints:R_0402_1005Metric"
			(at 160.02 116.84 0)
			(effects
				(font
					(size 1.27 1.27)
					(thickness 0.15)
				)
				(justify left bottom)
				(hide yes)
			)
		)
		(property "Datasheet" "https://www.bourns.com/docs/product-datasheets/cr.pdf"
			(at 157.48 116.84 0)
			(effects
				(font
					(size 1.27 1.27)
					(thickness 0.15)
				)
				(justify left bottom)
				(hide yes)
			)
		)
		(property "Description" "SMD Chip Resistor, 10 kohm, ± 1%, 62.5 mW, 0402 [1005 Metric], Thick Film, General Purpose"
			(at 175.26 96.52 0)
			(effects
				(font
					(size 1.27 1.27)
				)
				(hide yes)
			)
		)
		(property "Manufacturer" "Bourns"
			(at 152.4 116.84 0)
			(effects
				(font
					(size 1.27 1.27)
					(thickness 0.15)
				)
				(justify left bottom)
				(hide yes)
			)
		)
		(property "MPN" "CR0402-FX-1002GLF"
			(at 154.94 116.84 0)
			(effects
				(font
					(size 1.27 1.27)
					(thickness 0.15)
				)
				(justify left bottom)
				(hide yes)
			)
		)
		(property "Val" "10k"
			(at 176.53 100.33 90)
			(effects
				(font
					(size 1.27 1.27)
					(thickness 0.15)
				)
				(justify left)
			)
		)
		(property "License" "Apache-2.0"
			(at 149.86 116.84 0)
			(effects
				(font
					(size 1.27 1.27)
					(thickness 0.15)
				)
				(justify left bottom)
				(hide yes)
			)
		)
		(property "Author" "Antmicro"
			(at 147.32 116.84 0)
			(effects
				(font
					(size 1.27 1.27)
					(thickness 0.15)
				)
				(justify left bottom)
				(hide yes)
			)
		)
		(property "Tolerance" "1%"
			(at 165.1 116.84 0)
			(effects
				(font
					(size 1.27 1.27)
				)
				(justify left bottom)
				(hide yes)
			)
		)
		(pin "1"
		)
		(pin "2"
		)
		(instances
			(project "artix-dc-scm"
				(path ""
					(reference "R4")
					(unit 1)
				)
			)
		)
	)
	(symbol
		(lib_id "antmicroResonators:Resonator_12MHz_ABM8G")
		(at 151.13 125.73 0)
		(unit 1)
		(exclude_from_sim no)
		(in_bom yes)
		(on_board yes)
		(dnp no)
		(property "Reference" "Y1"
			(at 154.94 120.015 0)
			(effects
				(font
					(size 1.27 1.27)
				)
			)
		)
		(property "Value" "Resonator_12MHz_ABM8G"
			(at 166.37 138.43 0)
			(effects
				(font
					(size 1.27 1.27)
					(thickness 0.15)
				)
				(justify left bottom)
				(hide yes)
			)
		)
		(property "Footprint" "antmicro-footprints:Resonator_SMD_Abracon_ABM8G_3.2x2.5mm"
			(at 166.37 140.97 0)
			(effects
				(font
					(size 1.27 1.27)
					(thickness 0.15)
				)
				(justify left bottom)
				(hide yes)
			)
		)
		(property "Datasheet" "https://abracon.com/Resonators/ABM8G.pdf"
			(at 166.37 143.51 0)
			(effects
				(font
					(size 1.27 1.27)
					(thickness 0.15)
				)
				(justify left bottom)
				(hide yes)
			)
		)
		(property "Description" "Crystal, 12 MHz, SMT, 3.2mm x 2.5mm, 30 ppm, 18 pF, 20 ppm, ABM8G"
			(at 151.13 125.73 0)
			(effects
				(font
					(size 1.27 1.27)
				)
				(hide yes)
			)
		)
		(property "MPN" "ABM8G-12.000MHZ-18-D2Y-T"
			(at 166.37 133.35 0)
			(effects
				(font
					(size 1.27 1.27)
					(thickness 0.15)
				)
				(justify left bottom)
				(hide yes)
			)
		)
		(property "Manufacturer" "Abracon"
			(at 166.37 146.05 0)
			(effects
				(font
					(size 1.27 1.27)
					(thickness 0.15)
				)
				(justify left bottom)
				(hide yes)
			)
		)
		(property "Val" "12 MHz"
			(at 154.94 121.92 0)
			(effects
				(font
					(size 1.27 1.27)
					(thickness 0.15)
				)
			)
		)
		(property "Author" "Antmicro"
			(at 166.37 148.59 0)
			(effects
				(font
					(size 1.27 1.27)
					(thickness 0.15)
				)
				(justify left bottom)
				(hide yes)
			)
		)
		(property "License" "Apache-2.0"
			(at 166.37 151.13 0)
			(effects
				(font
					(size 1.27 1.27)
					(thickness 0.15)
				)
				(justify left bottom)
				(hide yes)
			)
		)
		(pin "1"
		)
		(pin "2"
		)
		(pin "3"
		)
		(pin "4"
		)
		(instances
			(project "artix-dc-scm"
				(path ""
					(reference "Y1")
					(unit 1)
				)
			)
		)
	)
	(symbol
		(lib_id "antmicroCapacitors0402:C_18p_0402")
		(at 160.02 132.08 90)
		(unit 1)
		(exclude_from_sim no)
		(in_bom yes)
		(on_board yes)
		(dnp no)
		(property "Reference" "C168"
			(at 160.655 127.635 90)
			(effects
				(font
					(size 1.27 1.27)
				)
				(justify right)
			)
		)
		(property "Value" "C_18p_0402"
			(at 170.18 111.76 0)
			(effects
				(font
					(size 1.27 1.27)
					(thickness 0.15)
				)
				(justify left bottom)
				(hide yes)
			)
		)
		(property "Footprint" "antmicro-footprints:C_0402_1005Metric"
			(at 172.72 111.76 0)
			(effects
				(font
					(size 1.27 1.27)
					(thickness 0.15)
				)
				(justify left bottom)
				(hide yes)
			)
		)
		(property "Datasheet" "https://product.samsungsem.com/mlcc/CL05C180JB51PN.do"
			(at 175.26 111.76 0)
			(effects
				(font
					(size 1.27 1.27)
					(thickness 0.15)
				)
				(justify left bottom)
				(hide yes)
			)
		)
		(property "Description" "SMD Multilayer Ceramic Capacitor, 18 pF, 50 V, 0402 [1005 Metric], ± 5%, C0G / NP0, MC"
			(at 160.02 132.08 0)
			(effects
				(font
					(size 1.27 1.27)
				)
				(hide yes)
			)
		)
		(property "Manufacturer" "Samsung Electro-Mechanics"
			(at 180.34 111.76 0)
			(effects
				(font
					(size 1.27 1.27)
					(thickness 0.15)
				)
				(justify left bottom)
				(hide yes)
			)
		)
		(property "MPN" "CL05C180JB51PNC"
			(at 177.8 111.76 0)
			(effects
				(font
					(size 1.27 1.27)
					(thickness 0.15)
				)
				(justify left bottom)
				(hide yes)
			)
		)
		(property "Val" "18p"
			(at 160.655 131.445 90)
			(effects
				(font
					(size 1.27 1.27)
					(thickness 0.15)
				)
				(justify right)
			)
		)
		(property "License" "Apache-2.0"
			(at 182.88 111.76 0)
			(effects
				(font
					(size 1.27 1.27)
					(thickness 0.15)
				)
				(justify left bottom)
				(hide yes)
			)
		)
		(property "Author" "Antmicro"
			(at 185.42 111.76 0)
			(effects
				(font
					(size 1.27 1.27)
					(thickness 0.15)
				)
				(justify left bottom)
				(hide yes)
			)
		)
		(property "Voltage" ""
			(at 187.96 111.76 0)
			(effects
				(font
					(size 1.27 1.27)
				)
				(justify left bottom)
				(hide yes)
			)
		)
		(property "Dielectric" ""
			(at 190.5 111.76 0)
			(effects
				(font
					(size 1.27 1.27)
				)
				(justify left bottom)
				(hide yes)
			)
		)
		(pin "1"
		)
		(pin "2"
		)
		(instances
			(project "artix-dc-scm"
				(path ""
					(reference "C168")
					(unit 1)
				)
			)
		)
	)
	(symbol
		(lib_id "antmicroCapacitors0402:C_18p_0402")
		(at 146.05 132.08 90)
		(unit 1)
		(exclude_from_sim no)
		(in_bom yes)
		(on_board yes)
		(dnp no)
		(property "Reference" "C166"
			(at 146.685 127.635 90)
			(effects
				(font
					(size 1.27 1.27)
				)
				(justify right)
			)
		)
		(property "Value" "C_18p_0402"
			(at 156.21 111.76 0)
			(effects
				(font
					(size 1.27 1.27)
					(thickness 0.15)
				)
				(justify left bottom)
				(hide yes)
			)
		)
		(property "Footprint" "antmicro-footprints:C_0402_1005Metric"
			(at 158.75 111.76 0)
			(effects
				(font
					(size 1.27 1.27)
					(thickness 0.15)
				)
				(justify left bottom)
				(hide yes)
			)
		)
		(property "Datasheet" "https://product.samsungsem.com/mlcc/CL05C180JB51PN.do"
			(at 161.29 111.76 0)
			(effects
				(font
					(size 1.27 1.27)
					(thickness 0.15)
				)
				(justify left bottom)
				(hide yes)
			)
		)
		(property "Description" "SMD Multilayer Ceramic Capacitor, 18 pF, 50 V, 0402 [1005 Metric], ± 5%, C0G / NP0, MC"
			(at 146.05 132.08 0)
			(effects
				(font
					(size 1.27 1.27)
				)
				(hide yes)
			)
		)
		(property "Manufacturer" "Samsung Electro-Mechanics"
			(at 166.37 111.76 0)
			(effects
				(font
					(size 1.27 1.27)
					(thickness 0.15)
				)
				(justify left bottom)
				(hide yes)
			)
		)
		(property "MPN" "CL05C180JB51PNC"
			(at 163.83 111.76 0)
			(effects
				(font
					(size 1.27 1.27)
					(thickness 0.15)
				)
				(justify left bottom)
				(hide yes)
			)
		)
		(property "Val" "18p"
			(at 146.685 131.445 90)
			(effects
				(font
					(size 1.27 1.27)
					(thickness 0.15)
				)
				(justify right)
			)
		)
		(property "License" "Apache-2.0"
			(at 168.91 111.76 0)
			(effects
				(font
					(size 1.27 1.27)
					(thickness 0.15)
				)
				(justify left bottom)
				(hide yes)
			)
		)
		(property "Author" "Antmicro"
			(at 171.45 111.76 0)
			(effects
				(font
					(size 1.27 1.27)
					(thickness 0.15)
				)
				(justify left bottom)
				(hide yes)
			)
		)
		(property "Voltage" ""
			(at 173.99 111.76 0)
			(effects
				(font
					(size 1.27 1.27)
				)
				(justify left bottom)
				(hide yes)
			)
		)
		(property "Dielectric" ""
			(at 176.53 111.76 0)
			(effects
				(font
					(size 1.27 1.27)
				)
				(justify left bottom)
				(hide yes)
			)
		)
		(pin "1"
		)
		(pin "2"
		)
		(instances
			(project "artix-dc-scm"
				(path ""
					(reference "C166")
					(unit 1)
				)
			)
		)
	)
	(symbol
		(lib_id "antmicropower:GND")
		(at 146.05 132.08 0)
		(unit 1)
		(exclude_from_sim no)
		(in_bom yes)
		(on_board yes)
		(dnp no)
		(property "Reference" "#PWR0139"
			(at 146.05 138.43 0)
			(effects
				(font
					(size 1.27 1.27)
				)
				(hide yes)
			)
		)
		(property "Value" "GND"
			(at 146.05 135.89 0)
			(effects
				(font
					(size 1.27 1.27)
				)
			)
		)
		(property "Footprint" ""
			(at 146.05 132.08 0)
			(effects
				(font
					(size 1.27 1.27)
				)
				(hide yes)
			)
		)
		(property "Datasheet" ""
			(at 146.05 132.08 0)
			(effects
				(font
					(size 1.27 1.27)
				)
				(hide yes)
			)
		)
		(property "Description" ""
			(at 146.05 132.08 0)
			(effects
				(font
					(size 1.27 1.27)
				)
				(hide yes)
			)
		)
		(property "Author" "Antmicro"
			(at 154.94 139.7 0)
			(effects
				(font
					(size 1.27 1.27)
					(thickness 0.15)
				)
				(justify left bottom)
				(hide yes)
			)
		)
		(property "License" "Apache-2.0"
			(at 154.94 142.24 0)
			(effects
				(font
					(size 1.27 1.27)
					(thickness 0.15)
				)
				(justify left bottom)
				(hide yes)
			)
		)
		(pin "1"
		)
		(instances
			(project "artix-dc-scm"
				(path ""
					(reference "#PWR0139")
					(unit 1)
				)
			)
		)
	)
	(symbol
		(lib_id "antmicropower:GND")
		(at 160.02 132.08 0)
		(unit 1)
		(exclude_from_sim no)
		(in_bom yes)
		(on_board yes)
		(dnp no)
		(property "Reference" "#PWR0143"
			(at 160.02 138.43 0)
			(effects
				(font
					(size 1.27 1.27)
				)
				(hide yes)
			)
		)
		(property "Value" "GND"
			(at 160.02 135.89 0)
			(effects
				(font
					(size 1.27 1.27)
				)
			)
		)
		(property "Footprint" ""
			(at 160.02 132.08 0)
			(effects
				(font
					(size 1.27 1.27)
				)
				(hide yes)
			)
		)
		(property "Datasheet" ""
			(at 160.02 132.08 0)
			(effects
				(font
					(size 1.27 1.27)
				)
				(hide yes)
			)
		)
		(property "Description" ""
			(at 160.02 132.08 0)
			(effects
				(font
					(size 1.27 1.27)
				)
				(hide yes)
			)
		)
		(property "Author" "Antmicro"
			(at 168.91 139.7 0)
			(effects
				(font
					(size 1.27 1.27)
					(thickness 0.15)
				)
				(justify left bottom)
				(hide yes)
			)
		)
		(property "License" "Apache-2.0"
			(at 168.91 142.24 0)
			(effects
				(font
					(size 1.27 1.27)
					(thickness 0.15)
				)
				(justify left bottom)
				(hide yes)
			)
		)
		(pin "1"
		)
		(instances
			(project "artix-dc-scm"
				(path ""
					(reference "#PWR0143")
					(unit 1)
				)
			)
		)
	)
	(symbol
		(lib_id "antmicropower:GND")
		(at 154.94 132.08 0)
		(unit 1)
		(exclude_from_sim no)
		(in_bom yes)
		(on_board yes)
		(dnp no)
		(property "Reference" "#PWR0142"
			(at 154.94 138.43 0)
			(effects
				(font
					(size 1.27 1.27)
				)
				(hide yes)
			)
		)
		(property "Value" "GND"
			(at 154.94 135.89 0)
			(effects
				(font
					(size 1.27 1.27)
				)
			)
		)
		(property "Footprint" ""
			(at 154.94 132.08 0)
			(effects
				(font
					(size 1.27 1.27)
				)
				(hide yes)
			)
		)
		(property "Datasheet" ""
			(at 154.94 132.08 0)
			(effects
				(font
					(size 1.27 1.27)
				)
				(hide yes)
			)
		)
		(property "Description" ""
			(at 154.94 132.08 0)
			(effects
				(font
					(size 1.27 1.27)
				)
				(hide yes)
			)
		)
		(property "Author" "Antmicro"
			(at 163.83 139.7 0)
			(effects
				(font
					(size 1.27 1.27)
					(thickness 0.15)
				)
				(justify left bottom)
				(hide yes)
			)
		)
		(property "License" "Apache-2.0"
			(at 163.83 142.24 0)
			(effects
				(font
					(size 1.27 1.27)
					(thickness 0.15)
				)
				(justify left bottom)
				(hide yes)
			)
		)
		(pin "1"
		)
		(instances
			(project "artix-dc-scm"
				(path ""
					(reference "#PWR0142")
					(unit 1)
				)
			)
		)
	)
	(symbol
		(lib_id "antmicropower:GND")
		(at 182.88 132.08 0)
		(unit 1)
		(exclude_from_sim no)
		(in_bom yes)
		(on_board yes)
		(dnp no)
		(property "Reference" "#PWR0144"
			(at 182.88 138.43 0)
			(effects
				(font
					(size 1.27 1.27)
				)
				(hide yes)
			)
		)
		(property "Value" "GND"
			(at 182.88 135.89 0)
			(effects
				(font
					(size 1.27 1.27)
				)
			)
		)
		(property "Footprint" ""
			(at 182.88 132.08 0)
			(effects
				(font
					(size 1.27 1.27)
				)
				(hide yes)
			)
		)
		(property "Datasheet" ""
			(at 182.88 132.08 0)
			(effects
				(font
					(size 1.27 1.27)
				)
				(hide yes)
			)
		)
		(property "Description" ""
			(at 182.88 132.08 0)
			(effects
				(font
					(size 1.27 1.27)
				)
				(hide yes)
			)
		)
		(property "Author" "Antmicro"
			(at 191.77 139.7 0)
			(effects
				(font
					(size 1.27 1.27)
					(thickness 0.15)
				)
				(justify left bottom)
				(hide yes)
			)
		)
		(property "License" "Apache-2.0"
			(at 191.77 142.24 0)
			(effects
				(font
					(size 1.27 1.27)
					(thickness 0.15)
				)
				(justify left bottom)
				(hide yes)
			)
		)
		(pin "1"
		)
		(instances
			(project "artix-dc-scm"
				(path ""
					(reference "#PWR0144")
					(unit 1)
				)
			)
		)
	)
	(symbol
		(lib_id "antmicroCapacitors0402:C_100n_0402")
		(at 386.08 30.48 90)
		(unit 1)
		(exclude_from_sim no)
		(in_bom yes)
		(on_board yes)
		(dnp no)
		(property "Reference" "C249"
			(at 386.715 26.035 90)
			(effects
				(font
					(size 1.27 1.27)
				)
				(justify right)
			)
		)
		(property "Value" "C_100n_0402"
			(at 396.24 10.16 0)
			(effects
				(font
					(size 1.27 1.27)
					(thickness 0.15)
				)
				(justify left bottom)
				(hide yes)
			)
		)
		(property "Footprint" "antmicro-footprints:C_0402_1005Metric"
			(at 398.78 10.16 0)
			(effects
				(font
					(size 1.27 1.27)
					(thickness 0.15)
				)
				(justify left bottom)
				(hide yes)
			)
		)
		(property "Datasheet" "https://www.murata.com/products/productdetail?partno=GRM155R61H104KE14%23"
			(at 401.32 10.16 0)
			(effects
				(font
					(size 1.27 1.27)
					(thickness 0.15)
				)
				(justify left bottom)
				(hide yes)
			)
		)
		(property "Description" "SMD Multilayer Ceramic Capacitor, 0.1 µF, 50 V, 0402 [1005 Metric], ± 10%, X5R, GRM Series"
			(at 386.08 30.48 0)
			(effects
				(font
					(size 1.27 1.27)
				)
				(hide yes)
			)
		)
		(property "Manufacturer" "Murata"
			(at 406.4 10.16 0)
			(effects
				(font
					(size 1.27 1.27)
					(thickness 0.15)
				)
				(justify left bottom)
				(hide yes)
			)
		)
		(property "MPN" "GRM155R61H104KE14D"
			(at 403.86 10.16 0)
			(effects
				(font
					(size 1.27 1.27)
					(thickness 0.15)
				)
				(justify left bottom)
				(hide yes)
			)
		)
		(property "Val" "100n"
			(at 386.715 29.845 90)
			(effects
				(font
					(size 1.27 1.27)
					(thickness 0.15)
				)
				(justify right)
			)
		)
		(property "License" "Apache-2.0"
			(at 408.94 10.16 0)
			(effects
				(font
					(size 1.27 1.27)
					(thickness 0.15)
				)
				(justify left bottom)
				(hide yes)
			)
		)
		(property "Author" "Antmicro"
			(at 411.48 10.16 0)
			(effects
				(font
					(size 1.27 1.27)
					(thickness 0.15)
				)
				(justify left bottom)
				(hide yes)
			)
		)
		(property "Voltage" "50V"
			(at 414.02 10.16 0)
			(effects
				(font
					(size 1.27 1.27)
				)
				(justify left bottom)
				(hide yes)
			)
		)
		(property "Dielectric" "X5R"
			(at 416.56 10.16 0)
			(effects
				(font
					(size 1.27 1.27)
				)
				(justify left bottom)
				(hide yes)
			)
		)
		(pin "1"
		)
		(pin "2"
		)
		(instances
			(project "artix-dc-scm"
				(path ""
					(reference "C249")
					(unit 1)
				)
			)
		)
	)
	(symbol
		(lib_id "antmicropower:GND")
		(at 386.08 30.48 0)
		(unit 1)
		(exclude_from_sim no)
		(in_bom yes)
		(on_board yes)
		(dnp no)
		(property "Reference" "#PWR0155"
			(at 386.08 36.83 0)
			(effects
				(font
					(size 1.27 1.27)
				)
				(hide yes)
			)
		)
		(property "Value" "GND"
			(at 386.08 34.29 0)
			(effects
				(font
					(size 1.27 1.27)
				)
			)
		)
		(property "Footprint" ""
			(at 386.08 30.48 0)
			(effects
				(font
					(size 1.27 1.27)
				)
				(hide yes)
			)
		)
		(property "Datasheet" ""
			(at 386.08 30.48 0)
			(effects
				(font
					(size 1.27 1.27)
				)
				(hide yes)
			)
		)
		(property "Description" ""
			(at 386.08 30.48 0)
			(effects
				(font
					(size 1.27 1.27)
				)
				(hide yes)
			)
		)
		(property "Author" "Antmicro"
			(at 394.97 38.1 0)
			(effects
				(font
					(size 1.27 1.27)
					(thickness 0.15)
				)
				(justify left bottom)
				(hide yes)
			)
		)
		(property "License" "Apache-2.0"
			(at 394.97 40.64 0)
			(effects
				(font
					(size 1.27 1.27)
					(thickness 0.15)
				)
				(justify left bottom)
				(hide yes)
			)
		)
		(pin "1"
		)
		(instances
			(project "artix-dc-scm"
				(path ""
					(reference "#PWR0155")
					(unit 1)
				)
			)
		)
	)
	(symbol
		(lib_id "antmicroCapacitors0402:C_100n_0402")
		(at 386.08 123.19 90)
		(unit 1)
		(exclude_from_sim no)
		(in_bom yes)
		(on_board yes)
		(dnp no)
		(property "Reference" "C248"
			(at 386.715 118.745 90)
			(effects
				(font
					(size 1.27 1.27)
				)
				(justify right)
			)
		)
		(property "Value" "C_100n_0402"
			(at 396.24 102.87 0)
			(effects
				(font
					(size 1.27 1.27)
					(thickness 0.15)
				)
				(justify left bottom)
				(hide yes)
			)
		)
		(property "Footprint" "antmicro-footprints:C_0402_1005Metric"
			(at 398.78 102.87 0)
			(effects
				(font
					(size 1.27 1.27)
					(thickness 0.15)
				)
				(justify left bottom)
				(hide yes)
			)
		)
		(property "Datasheet" "https://www.murata.com/products/productdetail?partno=GRM155R61H104KE14%23"
			(at 401.32 102.87 0)
			(effects
				(font
					(size 1.27 1.27)
					(thickness 0.15)
				)
				(justify left bottom)
				(hide yes)
			)
		)
		(property "Description" "SMD Multilayer Ceramic Capacitor, 0.1 µF, 50 V, 0402 [1005 Metric], ± 10%, X5R, GRM Series"
			(at 386.08 123.19 0)
			(effects
				(font
					(size 1.27 1.27)
				)
				(hide yes)
			)
		)
		(property "Manufacturer" "Murata"
			(at 406.4 102.87 0)
			(effects
				(font
					(size 1.27 1.27)
					(thickness 0.15)
				)
				(justify left bottom)
				(hide yes)
			)
		)
		(property "MPN" "GRM155R61H104KE14D"
			(at 403.86 102.87 0)
			(effects
				(font
					(size 1.27 1.27)
					(thickness 0.15)
				)
				(justify left bottom)
				(hide yes)
			)
		)
		(property "Val" "100n"
			(at 386.715 122.555 90)
			(effects
				(font
					(size 1.27 1.27)
					(thickness 0.15)
				)
				(justify right)
			)
		)
		(property "License" "Apache-2.0"
			(at 408.94 102.87 0)
			(effects
				(font
					(size 1.27 1.27)
					(thickness 0.15)
				)
				(justify left bottom)
				(hide yes)
			)
		)
		(property "Author" "Antmicro"
			(at 411.48 102.87 0)
			(effects
				(font
					(size 1.27 1.27)
					(thickness 0.15)
				)
				(justify left bottom)
				(hide yes)
			)
		)
		(property "Voltage" "50V"
			(at 414.02 102.87 0)
			(effects
				(font
					(size 1.27 1.27)
				)
				(justify left bottom)
				(hide yes)
			)
		)
		(property "Dielectric" "X5R"
			(at 416.56 102.87 0)
			(effects
				(font
					(size 1.27 1.27)
				)
				(justify left bottom)
				(hide yes)
			)
		)
		(pin "1"
		)
		(pin "2"
		)
		(instances
			(project "artix-dc-scm"
				(path ""
					(reference "C248")
					(unit 1)
				)
			)
		)
	)
	(symbol
		(lib_id "antmicroResistors0402:R_22R_0402")
		(at 229.87 31.75 0)
		(unit 1)
		(exclude_from_sim no)
		(in_bom yes)
		(on_board yes)
		(dnp no)
		(property "Reference" "R160"
			(at 237.49 30.48 0)
			(effects
				(font
					(size 1.27 1.27)
				)
			)
		)
		(property "Value" "R_22R_0402"
			(at 250.19 44.45 0)
			(effects
				(font
					(size 1.27 1.27)
					(thickness 0.15)
				)
				(justify left bottom)
				(hide yes)
			)
		)
		(property "Footprint" "antmicro-footprints:R_0402_1005Metric"
			(at 250.19 46.99 0)
			(effects
				(font
					(size 1.27 1.27)
					(thickness 0.15)
				)
				(justify left bottom)
				(hide yes)
			)
		)
		(property "Datasheet" "https://www.bourns.com/docs/product-datasheets/cr.pdf"
			(at 250.19 49.53 0)
			(effects
				(font
					(size 1.27 1.27)
					(thickness 0.15)
				)
				(justify left bottom)
				(hide yes)
			)
		)
		(property "Description" "SMD Chip Resistor, 22 ohm, ± 1%, 62.5 mW, 0402 [1005 Metric], Thick Film, General Purpose"
			(at 229.87 31.75 0)
			(effects
				(font
					(size 1.27 1.27)
				)
				(hide yes)
			)
		)
		(property "Manufacturer" "Bourns"
			(at 250.19 54.61 0)
			(effects
				(font
					(size 1.27 1.27)
					(thickness 0.15)
				)
				(justify left bottom)
				(hide yes)
			)
		)
		(property "MPN" "CR0402-FX-22R0GLF"
			(at 250.19 52.07 0)
			(effects
				(font
					(size 1.27 1.27)
					(thickness 0.15)
				)
				(justify left bottom)
				(hide yes)
			)
		)
		(property "Val" "22R"
			(at 226.06 31.75 0)
			(effects
				(font
					(size 1.27 1.27)
					(thickness 0.15)
				)
				(justify left bottom)
			)
		)
		(property "License" "Apache-2.0"
			(at 250.19 57.15 0)
			(effects
				(font
					(size 1.27 1.27)
					(thickness 0.15)
				)
				(justify left bottom)
				(hide yes)
			)
		)
		(property "Author" "Antmicro"
			(at 250.19 59.69 0)
			(effects
				(font
					(size 1.27 1.27)
					(thickness 0.15)
				)
				(justify left bottom)
				(hide yes)
			)
		)
		(property "Tolerance" "1%"
			(at 250.19 41.91 0)
			(effects
				(font
					(size 1.27 1.27)
				)
				(justify left bottom)
				(hide yes)
			)
		)
		(pin "1"
		)
		(pin "2"
		)
		(instances
			(project "artix-dc-scm"
				(path ""
					(reference "R160")
					(unit 1)
				)
			)
		)
	)
	(symbol
		(lib_id "antmicroResistors0402:R_22R_0402")
		(at 229.87 34.29 0)
		(unit 1)
		(exclude_from_sim no)
		(in_bom yes)
		(on_board yes)
		(dnp no)
		(property "Reference" "R191"
			(at 237.49 33.02 0)
			(effects
				(font
					(size 1.27 1.27)
				)
			)
		)
		(property "Value" "R_22R_0402"
			(at 250.19 46.99 0)
			(effects
				(font
					(size 1.27 1.27)
					(thickness 0.15)
				)
				(justify left bottom)
				(hide yes)
			)
		)
		(property "Footprint" "antmicro-footprints:R_0402_1005Metric"
			(at 250.19 49.53 0)
			(effects
				(font
					(size 1.27 1.27)
					(thickness 0.15)
				)
				(justify left bottom)
				(hide yes)
			)
		)
		(property "Datasheet" "https://www.bourns.com/docs/product-datasheets/cr.pdf"
			(at 250.19 52.07 0)
			(effects
				(font
					(size 1.27 1.27)
					(thickness 0.15)
				)
				(justify left bottom)
				(hide yes)
			)
		)
		(property "Description" "SMD Chip Resistor, 22 ohm, ± 1%, 62.5 mW, 0402 [1005 Metric], Thick Film, General Purpose"
			(at 229.87 34.29 0)
			(effects
				(font
					(size 1.27 1.27)
				)
				(hide yes)
			)
		)
		(property "Manufacturer" "Bourns"
			(at 250.19 57.15 0)
			(effects
				(font
					(size 1.27 1.27)
					(thickness 0.15)
				)
				(justify left bottom)
				(hide yes)
			)
		)
		(property "MPN" "CR0402-FX-22R0GLF"
			(at 250.19 54.61 0)
			(effects
				(font
					(size 1.27 1.27)
					(thickness 0.15)
				)
				(justify left bottom)
				(hide yes)
			)
		)
		(property "Val" "22R"
			(at 226.06 34.29 0)
			(effects
				(font
					(size 1.27 1.27)
					(thickness 0.15)
				)
				(justify left bottom)
			)
		)
		(property "License" "Apache-2.0"
			(at 250.19 59.69 0)
			(effects
				(font
					(size 1.27 1.27)
					(thickness 0.15)
				)
				(justify left bottom)
				(hide yes)
			)
		)
		(property "Author" "Antmicro"
			(at 250.19 62.23 0)
			(effects
				(font
					(size 1.27 1.27)
					(thickness 0.15)
				)
				(justify left bottom)
				(hide yes)
			)
		)
		(property "Tolerance" "1%"
			(at 250.19 44.45 0)
			(effects
				(font
					(size 1.27 1.27)
				)
				(justify left bottom)
				(hide yes)
			)
		)
		(pin "1"
		)
		(pin "2"
		)
		(instances
			(project "artix-dc-scm"
				(path ""
					(reference "R191")
					(unit 1)
				)
			)
		)
	)
	(symbol
		(lib_id "antmicroResistors0402:R_22R_0402")
		(at 229.87 36.83 0)
		(unit 1)
		(exclude_from_sim no)
		(in_bom yes)
		(on_board yes)
		(dnp no)
		(property "Reference" "R192"
			(at 237.49 35.56 0)
			(effects
				(font
					(size 1.27 1.27)
				)
			)
		)
		(property "Value" "R_22R_0402"
			(at 250.19 49.53 0)
			(effects
				(font
					(size 1.27 1.27)
					(thickness 0.15)
				)
				(justify left bottom)
				(hide yes)
			)
		)
		(property "Footprint" "antmicro-footprints:R_0402_1005Metric"
			(at 250.19 52.07 0)
			(effects
				(font
					(size 1.27 1.27)
					(thickness 0.15)
				)
				(justify left bottom)
				(hide yes)
			)
		)
		(property "Datasheet" "https://www.bourns.com/docs/product-datasheets/cr.pdf"
			(at 250.19 54.61 0)
			(effects
				(font
					(size 1.27 1.27)
					(thickness 0.15)
				)
				(justify left bottom)
				(hide yes)
			)
		)
		(property "Description" "SMD Chip Resistor, 22 ohm, ± 1%, 62.5 mW, 0402 [1005 Metric], Thick Film, General Purpose"
			(at 229.87 36.83 0)
			(effects
				(font
					(size 1.27 1.27)
				)
				(hide yes)
			)
		)
		(property "Manufacturer" "Bourns"
			(at 250.19 59.69 0)
			(effects
				(font
					(size 1.27 1.27)
					(thickness 0.15)
				)
				(justify left bottom)
				(hide yes)
			)
		)
		(property "MPN" "CR0402-FX-22R0GLF"
			(at 250.19 57.15 0)
			(effects
				(font
					(size 1.27 1.27)
					(thickness 0.15)
				)
				(justify left bottom)
				(hide yes)
			)
		)
		(property "Val" "22R"
			(at 226.06 36.83 0)
			(effects
				(font
					(size 1.27 1.27)
					(thickness 0.15)
				)
				(justify left bottom)
			)
		)
		(property "License" "Apache-2.0"
			(at 250.19 62.23 0)
			(effects
				(font
					(size 1.27 1.27)
					(thickness 0.15)
				)
				(justify left bottom)
				(hide yes)
			)
		)
		(property "Author" "Antmicro"
			(at 250.19 64.77 0)
			(effects
				(font
					(size 1.27 1.27)
					(thickness 0.15)
				)
				(justify left bottom)
				(hide yes)
			)
		)
		(property "Tolerance" "1%"
			(at 250.19 46.99 0)
			(effects
				(font
					(size 1.27 1.27)
				)
				(justify left bottom)
				(hide yes)
			)
		)
		(pin "1"
		)
		(pin "2"
		)
		(instances
			(project "artix-dc-scm"
				(path ""
					(reference "R192")
					(unit 1)
				)
			)
		)
	)
	(symbol
		(lib_id "antmicroResistors0402:R_22R_0402")
		(at 229.87 39.37 0)
		(unit 1)
		(exclude_from_sim no)
		(in_bom yes)
		(on_board yes)
		(dnp no)
		(property "Reference" "R193"
			(at 237.49 38.1 0)
			(effects
				(font
					(size 1.27 1.27)
				)
			)
		)
		(property "Value" "R_22R_0402"
			(at 250.19 52.07 0)
			(effects
				(font
					(size 1.27 1.27)
					(thickness 0.15)
				)
				(justify left bottom)
				(hide yes)
			)
		)
		(property "Footprint" "antmicro-footprints:R_0402_1005Metric"
			(at 250.19 54.61 0)
			(effects
				(font
					(size 1.27 1.27)
					(thickness 0.15)
				)
				(justify left bottom)
				(hide yes)
			)
		)
		(property "Datasheet" "https://www.bourns.com/docs/product-datasheets/cr.pdf"
			(at 250.19 57.15 0)
			(effects
				(font
					(size 1.27 1.27)
					(thickness 0.15)
				)
				(justify left bottom)
				(hide yes)
			)
		)
		(property "Description" "SMD Chip Resistor, 22 ohm, ± 1%, 62.5 mW, 0402 [1005 Metric], Thick Film, General Purpose"
			(at 229.87 39.37 0)
			(effects
				(font
					(size 1.27 1.27)
				)
				(hide yes)
			)
		)
		(property "Manufacturer" "Bourns"
			(at 250.19 62.23 0)
			(effects
				(font
					(size 1.27 1.27)
					(thickness 0.15)
				)
				(justify left bottom)
				(hide yes)
			)
		)
		(property "MPN" "CR0402-FX-22R0GLF"
			(at 250.19 59.69 0)
			(effects
				(font
					(size 1.27 1.27)
					(thickness 0.15)
				)
				(justify left bottom)
				(hide yes)
			)
		)
		(property "Val" "22R"
			(at 226.06 39.37 0)
			(effects
				(font
					(size 1.27 1.27)
					(thickness 0.15)
				)
				(justify left bottom)
			)
		)
		(property "License" "Apache-2.0"
			(at 250.19 64.77 0)
			(effects
				(font
					(size 1.27 1.27)
					(thickness 0.15)
				)
				(justify left bottom)
				(hide yes)
			)
		)
		(property "Author" "Antmicro"
			(at 250.19 67.31 0)
			(effects
				(font
					(size 1.27 1.27)
					(thickness 0.15)
				)
				(justify left bottom)
				(hide yes)
			)
		)
		(property "Tolerance" "1%"
			(at 250.19 49.53 0)
			(effects
				(font
					(size 1.27 1.27)
				)
				(justify left bottom)
				(hide yes)
			)
		)
		(pin "1"
		)
		(pin "2"
		)
		(instances
			(project "artix-dc-scm"
				(path ""
					(reference "R193")
					(unit 1)
				)
			)
		)
	)
	(symbol
		(lib_id "antmicroTestPoints:TP_1mm_SMD")
		(at 215.9 44.45 0)
		(unit 1)
		(exclude_from_sim no)
		(in_bom no)
		(on_board yes)
		(dnp no)
		(property "Reference" "TP8"
			(at 220.345 44.45 0)
			(effects
				(font
					(size 1.27 1.27)
				)
				(justify left)
			)
		)
		(property "Value" "TP_1mm_SMD"
			(at 215.9 46.99 0)
			(effects
				(font
					(size 1.27 1.27)
				)
				(hide yes)
			)
		)
		(property "Footprint" "antmicro-footprints:TP_SMD_1mm"
			(at 231.14 54.61 0)
			(effects
				(font
					(size 1.27 1.27)
					(thickness 0.15)
				)
				(justify left bottom)
				(hide yes)
			)
		)
		(property "Datasheet" ""
			(at 231.14 57.15 0)
			(effects
				(font
					(size 1.27 1.27)
					(thickness 0.15)
				)
				(justify left bottom)
				(hide yes)
			)
		)
		(property "Description" "Test point 1mm SMD"
			(at 215.9 44.45 0)
			(effects
				(font
					(size 1.27 1.27)
				)
				(hide yes)
			)
		)
		(property "MPN" ""
			(at 215.9 44.45 0)
			(effects
				(font
					(size 1.27 1.27)
				)
				(hide yes)
			)
		)
		(property "Manufacturer" ""
			(at 215.9 44.45 0)
			(effects
				(font
					(size 1.27 1.27)
				)
				(hide yes)
			)
		)
		(property "Author" "Antmicro"
			(at 231.14 59.69 0)
			(effects
				(font
					(size 1.27 1.27)
					(thickness 0.15)
				)
				(justify left bottom)
				(hide yes)
			)
		)
		(property "License" "Apache-2.0"
			(at 231.14 62.23 0)
			(effects
				(font
					(size 1.27 1.27)
					(thickness 0.15)
				)
				(justify left bottom)
				(hide yes)
			)
		)
		(pin "1"
		)
		(instances
			(project "artix-dc-scm"
				(path ""
					(reference "TP8")
					(unit 1)
				)
			)
		)
	)
	(symbol
		(lib_id "antmicroCapacitors0402:C_100n_0402")
		(at 147.32 45.72 90)
		(unit 1)
		(exclude_from_sim no)
		(in_bom yes)
		(on_board yes)
		(dnp no)
		(property "Reference" "C169"
			(at 147.955 41.275 90)
			(effects
				(font
					(size 1.27 1.27)
				)
				(justify right)
			)
		)
		(property "Value" "C_100n_0402"
			(at 157.48 25.4 0)
			(effects
				(font
					(size 1.27 1.27)
					(thickness 0.15)
				)
				(justify left bottom)
				(hide yes)
			)
		)
		(property "Footprint" "antmicro-footprints:C_0402_1005Metric"
			(at 160.02 25.4 0)
			(effects
				(font
					(size 1.27 1.27)
					(thickness 0.15)
				)
				(justify left bottom)
				(hide yes)
			)
		)
		(property "Datasheet" "https://www.murata.com/products/productdetail?partno=GRM155R61H104KE14%23"
			(at 162.56 25.4 0)
			(effects
				(font
					(size 1.27 1.27)
					(thickness 0.15)
				)
				(justify left bottom)
				(hide yes)
			)
		)
		(property "Description" "SMD Multilayer Ceramic Capacitor, 0.1 µF, 50 V, 0402 [1005 Metric], ± 10%, X5R, GRM Series"
			(at 147.32 45.72 0)
			(effects
				(font
					(size 1.27 1.27)
				)
				(hide yes)
			)
		)
		(property "Manufacturer" "Murata"
			(at 167.64 25.4 0)
			(effects
				(font
					(size 1.27 1.27)
					(thickness 0.15)
				)
				(justify left bottom)
				(hide yes)
			)
		)
		(property "MPN" "GRM155R61H104KE14D"
			(at 165.1 25.4 0)
			(effects
				(font
					(size 1.27 1.27)
					(thickness 0.15)
				)
				(justify left bottom)
				(hide yes)
			)
		)
		(property "Val" "100n"
			(at 147.955 45.085 90)
			(effects
				(font
					(size 1.27 1.27)
					(thickness 0.15)
				)
				(justify right)
			)
		)
		(property "License" "Apache-2.0"
			(at 170.18 25.4 0)
			(effects
				(font
					(size 1.27 1.27)
					(thickness 0.15)
				)
				(justify left bottom)
				(hide yes)
			)
		)
		(property "Author" "Antmicro"
			(at 172.72 25.4 0)
			(effects
				(font
					(size 1.27 1.27)
					(thickness 0.15)
				)
				(justify left bottom)
				(hide yes)
			)
		)
		(property "Voltage" "50V"
			(at 175.26 25.4 0)
			(effects
				(font
					(size 1.27 1.27)
				)
				(justify left bottom)
				(hide yes)
			)
		)
		(property "Dielectric" "X5R"
			(at 177.8 25.4 0)
			(effects
				(font
					(size 1.27 1.27)
				)
				(justify left bottom)
				(hide yes)
			)
		)
		(pin "1"
		)
		(pin "2"
		)
		(instances
			(project "artix-dc-scm"
				(path ""
					(reference "C169")
					(unit 1)
				)
			)
		)
	)
	(symbol
		(lib_id "antmicroCapacitors0402:C_100n_0402")
		(at 153.67 45.72 90)
		(unit 1)
		(exclude_from_sim no)
		(in_bom yes)
		(on_board yes)
		(dnp no)
		(property "Reference" "C170"
			(at 154.305 41.275 90)
			(effects
				(font
					(size 1.27 1.27)
				)
				(justify right)
			)
		)
		(property "Value" "C_100n_0402"
			(at 163.83 25.4 0)
			(effects
				(font
					(size 1.27 1.27)
					(thickness 0.15)
				)
				(justify left bottom)
				(hide yes)
			)
		)
		(property "Footprint" "antmicro-footprints:C_0402_1005Metric"
			(at 166.37 25.4 0)
			(effects
				(font
					(size 1.27 1.27)
					(thickness 0.15)
				)
				(justify left bottom)
				(hide yes)
			)
		)
		(property "Datasheet" "https://www.murata.com/products/productdetail?partno=GRM155R61H104KE14%23"
			(at 168.91 25.4 0)
			(effects
				(font
					(size 1.27 1.27)
					(thickness 0.15)
				)
				(justify left bottom)
				(hide yes)
			)
		)
		(property "Description" "SMD Multilayer Ceramic Capacitor, 0.1 µF, 50 V, 0402 [1005 Metric], ± 10%, X5R, GRM Series"
			(at 153.67 45.72 0)
			(effects
				(font
					(size 1.27 1.27)
				)
				(hide yes)
			)
		)
		(property "Manufacturer" "Murata"
			(at 173.99 25.4 0)
			(effects
				(font
					(size 1.27 1.27)
					(thickness 0.15)
				)
				(justify left bottom)
				(hide yes)
			)
		)
		(property "MPN" "GRM155R61H104KE14D"
			(at 171.45 25.4 0)
			(effects
				(font
					(size 1.27 1.27)
					(thickness 0.15)
				)
				(justify left bottom)
				(hide yes)
			)
		)
		(property "Val" "100n"
			(at 154.305 45.085 90)
			(effects
				(font
					(size 1.27 1.27)
					(thickness 0.15)
				)
				(justify right)
			)
		)
		(property "License" "Apache-2.0"
			(at 176.53 25.4 0)
			(effects
				(font
					(size 1.27 1.27)
					(thickness 0.15)
				)
				(justify left bottom)
				(hide yes)
			)
		)
		(property "Author" "Antmicro"
			(at 179.07 25.4 0)
			(effects
				(font
					(size 1.27 1.27)
					(thickness 0.15)
				)
				(justify left bottom)
				(hide yes)
			)
		)
		(property "Voltage" "50V"
			(at 181.61 25.4 0)
			(effects
				(font
					(size 1.27 1.27)
				)
				(justify left bottom)
				(hide yes)
			)
		)
		(property "Dielectric" "X5R"
			(at 184.15 25.4 0)
			(effects
				(font
					(size 1.27 1.27)
				)
				(justify left bottom)
				(hide yes)
			)
		)
		(pin "1"
		)
		(pin "2"
		)
		(instances
			(project "artix-dc-scm"
				(path ""
					(reference "C170")
					(unit 1)
				)
			)
		)
	)
	(symbol
		(lib_id "antmicroCapacitors0402:C_100n_0402")
		(at 161.29 45.72 90)
		(unit 1)
		(exclude_from_sim no)
		(in_bom yes)
		(on_board yes)
		(dnp no)
		(property "Reference" "C172"
			(at 161.925 41.275 90)
			(effects
				(font
					(size 1.27 1.27)
				)
				(justify right)
			)
		)
		(property "Value" "C_100n_0402"
			(at 171.45 25.4 0)
			(effects
				(font
					(size 1.27 1.27)
					(thickness 0.15)
				)
				(justify left bottom)
				(hide yes)
			)
		)
		(property "Footprint" "antmicro-footprints:C_0402_1005Metric"
			(at 173.99 25.4 0)
			(effects
				(font
					(size 1.27 1.27)
					(thickness 0.15)
				)
				(justify left bottom)
				(hide yes)
			)
		)
		(property "Datasheet" "https://www.murata.com/products/productdetail?partno=GRM155R61H104KE14%23"
			(at 176.53 25.4 0)
			(effects
				(font
					(size 1.27 1.27)
					(thickness 0.15)
				)
				(justify left bottom)
				(hide yes)
			)
		)
		(property "Description" "SMD Multilayer Ceramic Capacitor, 0.1 µF, 50 V, 0402 [1005 Metric], ± 10%, X5R, GRM Series"
			(at 161.29 45.72 0)
			(effects
				(font
					(size 1.27 1.27)
				)
				(hide yes)
			)
		)
		(property "Manufacturer" "Murata"
			(at 181.61 25.4 0)
			(effects
				(font
					(size 1.27 1.27)
					(thickness 0.15)
				)
				(justify left bottom)
				(hide yes)
			)
		)
		(property "MPN" "GRM155R61H104KE14D"
			(at 179.07 25.4 0)
			(effects
				(font
					(size 1.27 1.27)
					(thickness 0.15)
				)
				(justify left bottom)
				(hide yes)
			)
		)
		(property "Val" "100n"
			(at 161.925 45.085 90)
			(effects
				(font
					(size 1.27 1.27)
					(thickness 0.15)
				)
				(justify right)
			)
		)
		(property "License" "Apache-2.0"
			(at 184.15 25.4 0)
			(effects
				(font
					(size 1.27 1.27)
					(thickness 0.15)
				)
				(justify left bottom)
				(hide yes)
			)
		)
		(property "Author" "Antmicro"
			(at 186.69 25.4 0)
			(effects
				(font
					(size 1.27 1.27)
					(thickness 0.15)
				)
				(justify left bottom)
				(hide yes)
			)
		)
		(property "Voltage" "50V"
			(at 189.23 25.4 0)
			(effects
				(font
					(size 1.27 1.27)
				)
				(justify left bottom)
				(hide yes)
			)
		)
		(property "Dielectric" "X5R"
			(at 191.77 25.4 0)
			(effects
				(font
					(size 1.27 1.27)
				)
				(justify left bottom)
				(hide yes)
			)
		)
		(pin "1"
		)
		(pin "2"
		)
		(instances
			(project "artix-dc-scm"
				(path ""
					(reference "C172")
					(unit 1)
				)
			)
		)
	)
	(symbol
		(lib_id "antmicroCapacitors0402:C_100n_0402")
		(at 167.64 45.72 90)
		(unit 1)
		(exclude_from_sim no)
		(in_bom yes)
		(on_board yes)
		(dnp no)
		(property "Reference" "C173"
			(at 168.275 41.275 90)
			(effects
				(font
					(size 1.27 1.27)
				)
				(justify right)
			)
		)
		(property "Value" "C_100n_0402"
			(at 177.8 25.4 0)
			(effects
				(font
					(size 1.27 1.27)
					(thickness 0.15)
				)
				(justify left bottom)
				(hide yes)
			)
		)
		(property "Footprint" "antmicro-footprints:C_0402_1005Metric"
			(at 180.34 25.4 0)
			(effects
				(font
					(size 1.27 1.27)
					(thickness 0.15)
				)
				(justify left bottom)
				(hide yes)
			)
		)
		(property "Datasheet" "https://www.murata.com/products/productdetail?partno=GRM155R61H104KE14%23"
			(at 182.88 25.4 0)
			(effects
				(font
					(size 1.27 1.27)
					(thickness 0.15)
				)
				(justify left bottom)
				(hide yes)
			)
		)
		(property "Description" "SMD Multilayer Ceramic Capacitor, 0.1 µF, 50 V, 0402 [1005 Metric], ± 10%, X5R, GRM Series"
			(at 167.64 45.72 0)
			(effects
				(font
					(size 1.27 1.27)
				)
				(hide yes)
			)
		)
		(property "Manufacturer" "Murata"
			(at 187.96 25.4 0)
			(effects
				(font
					(size 1.27 1.27)
					(thickness 0.15)
				)
				(justify left bottom)
				(hide yes)
			)
		)
		(property "MPN" "GRM155R61H104KE14D"
			(at 185.42 25.4 0)
			(effects
				(font
					(size 1.27 1.27)
					(thickness 0.15)
				)
				(justify left bottom)
				(hide yes)
			)
		)
		(property "Val" "100n"
			(at 168.275 45.085 90)
			(effects
				(font
					(size 1.27 1.27)
					(thickness 0.15)
				)
				(justify right)
			)
		)
		(property "License" "Apache-2.0"
			(at 190.5 25.4 0)
			(effects
				(font
					(size 1.27 1.27)
					(thickness 0.15)
				)
				(justify left bottom)
				(hide yes)
			)
		)
		(property "Author" "Antmicro"
			(at 193.04 25.4 0)
			(effects
				(font
					(size 1.27 1.27)
					(thickness 0.15)
				)
				(justify left bottom)
				(hide yes)
			)
		)
		(property "Voltage" "50V"
			(at 195.58 25.4 0)
			(effects
				(font
					(size 1.27 1.27)
				)
				(justify left bottom)
				(hide yes)
			)
		)
		(property "Dielectric" "X5R"
			(at 198.12 25.4 0)
			(effects
				(font
					(size 1.27 1.27)
				)
				(justify left bottom)
				(hide yes)
			)
		)
		(pin "1"
		)
		(pin "2"
		)
		(instances
			(project "artix-dc-scm"
				(path ""
					(reference "C173")
					(unit 1)
				)
			)
		)
	)
	(symbol
		(lib_id "antmicroCapacitors0402:C_100n_0402")
		(at 175.26 45.72 90)
		(unit 1)
		(exclude_from_sim no)
		(in_bom yes)
		(on_board yes)
		(dnp no)
		(property "Reference" "C174"
			(at 175.895 41.275 90)
			(effects
				(font
					(size 1.27 1.27)
				)
				(justify right)
			)
		)
		(property "Value" "C_100n_0402"
			(at 185.42 25.4 0)
			(effects
				(font
					(size 1.27 1.27)
					(thickness 0.15)
				)
				(justify left bottom)
				(hide yes)
			)
		)
		(property "Footprint" "antmicro-footprints:C_0402_1005Metric"
			(at 187.96 25.4 0)
			(effects
				(font
					(size 1.27 1.27)
					(thickness 0.15)
				)
				(justify left bottom)
				(hide yes)
			)
		)
		(property "Datasheet" "https://www.murata.com/products/productdetail?partno=GRM155R61H104KE14%23"
			(at 190.5 25.4 0)
			(effects
				(font
					(size 1.27 1.27)
					(thickness 0.15)
				)
				(justify left bottom)
				(hide yes)
			)
		)
		(property "Description" "SMD Multilayer Ceramic Capacitor, 0.1 µF, 50 V, 0402 [1005 Metric], ± 10%, X5R, GRM Series"
			(at 175.26 45.72 0)
			(effects
				(font
					(size 1.27 1.27)
				)
				(hide yes)
			)
		)
		(property "Manufacturer" "Murata"
			(at 195.58 25.4 0)
			(effects
				(font
					(size 1.27 1.27)
					(thickness 0.15)
				)
				(justify left bottom)
				(hide yes)
			)
		)
		(property "MPN" "GRM155R61H104KE14D"
			(at 193.04 25.4 0)
			(effects
				(font
					(size 1.27 1.27)
					(thickness 0.15)
				)
				(justify left bottom)
				(hide yes)
			)
		)
		(property "Val" "100n"
			(at 175.895 45.085 90)
			(effects
				(font
					(size 1.27 1.27)
					(thickness 0.15)
				)
				(justify right)
			)
		)
		(property "License" "Apache-2.0"
			(at 198.12 25.4 0)
			(effects
				(font
					(size 1.27 1.27)
					(thickness 0.15)
				)
				(justify left bottom)
				(hide yes)
			)
		)
		(property "Author" "Antmicro"
			(at 200.66 25.4 0)
			(effects
				(font
					(size 1.27 1.27)
					(thickness 0.15)
				)
				(justify left bottom)
				(hide yes)
			)
		)
		(property "Voltage" "50V"
			(at 203.2 25.4 0)
			(effects
				(font
					(size 1.27 1.27)
				)
				(justify left bottom)
				(hide yes)
			)
		)
		(property "Dielectric" "X5R"
			(at 205.74 25.4 0)
			(effects
				(font
					(size 1.27 1.27)
				)
				(justify left bottom)
				(hide yes)
			)
		)
		(pin "1"
		)
		(pin "2"
		)
		(instances
			(project "artix-dc-scm"
				(path ""
					(reference "C174")
					(unit 1)
				)
			)
		)
	)
	(symbol
		(lib_id "antmicropower:GND")
		(at 147.32 45.72 0)
		(unit 1)
		(exclude_from_sim no)
		(in_bom yes)
		(on_board yes)
		(dnp no)
		(property "Reference" "#PWR0146"
			(at 147.32 52.07 0)
			(effects
				(font
					(size 1.27 1.27)
				)
				(hide yes)
			)
		)
		(property "Value" "GND"
			(at 147.32 49.53 0)
			(effects
				(font
					(size 1.27 1.27)
				)
			)
		)
		(property "Footprint" ""
			(at 147.32 45.72 0)
			(effects
				(font
					(size 1.27 1.27)
				)
				(hide yes)
			)
		)
		(property "Datasheet" ""
			(at 147.32 45.72 0)
			(effects
				(font
					(size 1.27 1.27)
				)
				(hide yes)
			)
		)
		(property "Description" ""
			(at 147.32 45.72 0)
			(effects
				(font
					(size 1.27 1.27)
				)
				(hide yes)
			)
		)
		(property "Author" "Antmicro"
			(at 156.21 53.34 0)
			(effects
				(font
					(size 1.27 1.27)
					(thickness 0.15)
				)
				(justify left bottom)
				(hide yes)
			)
		)
		(property "License" "Apache-2.0"
			(at 156.21 55.88 0)
			(effects
				(font
					(size 1.27 1.27)
					(thickness 0.15)
				)
				(justify left bottom)
				(hide yes)
			)
		)
		(pin "1"
		)
		(instances
			(project "artix-dc-scm"
				(path ""
					(reference "#PWR0146")
					(unit 1)
				)
			)
		)
	)
	(symbol
		(lib_id "antmicropower:GND")
		(at 153.67 45.72 0)
		(unit 1)
		(exclude_from_sim no)
		(in_bom yes)
		(on_board yes)
		(dnp no)
		(property "Reference" "#PWR0147"
			(at 153.67 52.07 0)
			(effects
				(font
					(size 1.27 1.27)
				)
				(hide yes)
			)
		)
		(property "Value" "GND"
			(at 153.67 49.53 0)
			(effects
				(font
					(size 1.27 1.27)
				)
			)
		)
		(property "Footprint" ""
			(at 153.67 45.72 0)
			(effects
				(font
					(size 1.27 1.27)
				)
				(hide yes)
			)
		)
		(property "Datasheet" ""
			(at 153.67 45.72 0)
			(effects
				(font
					(size 1.27 1.27)
				)
				(hide yes)
			)
		)
		(property "Description" ""
			(at 153.67 45.72 0)
			(effects
				(font
					(size 1.27 1.27)
				)
				(hide yes)
			)
		)
		(property "Author" "Antmicro"
			(at 162.56 53.34 0)
			(effects
				(font
					(size 1.27 1.27)
					(thickness 0.15)
				)
				(justify left bottom)
				(hide yes)
			)
		)
		(property "License" "Apache-2.0"
			(at 162.56 55.88 0)
			(effects
				(font
					(size 1.27 1.27)
					(thickness 0.15)
				)
				(justify left bottom)
				(hide yes)
			)
		)
		(pin "1"
		)
		(instances
			(project "artix-dc-scm"
				(path ""
					(reference "#PWR0147")
					(unit 1)
				)
			)
		)
	)
	(symbol
		(lib_id "antmicropower:GND")
		(at 161.29 45.72 0)
		(unit 1)
		(exclude_from_sim no)
		(in_bom yes)
		(on_board yes)
		(dnp no)
		(property "Reference" "#PWR0148"
			(at 161.29 52.07 0)
			(effects
				(font
					(size 1.27 1.27)
				)
				(hide yes)
			)
		)
		(property "Value" "GND"
			(at 161.29 49.53 0)
			(effects
				(font
					(size 1.27 1.27)
				)
			)
		)
		(property "Footprint" ""
			(at 161.29 45.72 0)
			(effects
				(font
					(size 1.27 1.27)
				)
				(hide yes)
			)
		)
		(property "Datasheet" ""
			(at 161.29 45.72 0)
			(effects
				(font
					(size 1.27 1.27)
				)
				(hide yes)
			)
		)
		(property "Description" ""
			(at 161.29 45.72 0)
			(effects
				(font
					(size 1.27 1.27)
				)
				(hide yes)
			)
		)
		(property "Author" "Antmicro"
			(at 170.18 53.34 0)
			(effects
				(font
					(size 1.27 1.27)
					(thickness 0.15)
				)
				(justify left bottom)
				(hide yes)
			)
		)
		(property "License" "Apache-2.0"
			(at 170.18 55.88 0)
			(effects
				(font
					(size 1.27 1.27)
					(thickness 0.15)
				)
				(justify left bottom)
				(hide yes)
			)
		)
		(pin "1"
		)
		(instances
			(project "artix-dc-scm"
				(path ""
					(reference "#PWR0148")
					(unit 1)
				)
			)
		)
	)
	(symbol
		(lib_id "antmicropower:GND")
		(at 167.64 45.72 0)
		(unit 1)
		(exclude_from_sim no)
		(in_bom yes)
		(on_board yes)
		(dnp no)
		(property "Reference" "#PWR0149"
			(at 167.64 52.07 0)
			(effects
				(font
					(size 1.27 1.27)
				)
				(hide yes)
			)
		)
		(property "Value" "GND"
			(at 167.64 49.53 0)
			(effects
				(font
					(size 1.27 1.27)
				)
			)
		)
		(property "Footprint" ""
			(at 167.64 45.72 0)
			(effects
				(font
					(size 1.27 1.27)
				)
				(hide yes)
			)
		)
		(property "Datasheet" ""
			(at 167.64 45.72 0)
			(effects
				(font
					(size 1.27 1.27)
				)
				(hide yes)
			)
		)
		(property "Description" ""
			(at 167.64 45.72 0)
			(effects
				(font
					(size 1.27 1.27)
				)
				(hide yes)
			)
		)
		(property "Author" "Antmicro"
			(at 176.53 53.34 0)
			(effects
				(font
					(size 1.27 1.27)
					(thickness 0.15)
				)
				(justify left bottom)
				(hide yes)
			)
		)
		(property "License" "Apache-2.0"
			(at 176.53 55.88 0)
			(effects
				(font
					(size 1.27 1.27)
					(thickness 0.15)
				)
				(justify left bottom)
				(hide yes)
			)
		)
		(pin "1"
		)
		(instances
			(project "artix-dc-scm"
				(path ""
					(reference "#PWR0149")
					(unit 1)
				)
			)
		)
	)
	(symbol
		(lib_id "antmicropower:GND")
		(at 175.26 45.72 0)
		(unit 1)
		(exclude_from_sim no)
		(in_bom yes)
		(on_board yes)
		(dnp no)
		(property "Reference" "#PWR0150"
			(at 175.26 52.07 0)
			(effects
				(font
					(size 1.27 1.27)
				)
				(hide yes)
			)
		)
		(property "Value" "GND"
			(at 175.26 49.53 0)
			(effects
				(font
					(size 1.27 1.27)
				)
			)
		)
		(property "Footprint" ""
			(at 175.26 45.72 0)
			(effects
				(font
					(size 1.27 1.27)
				)
				(hide yes)
			)
		)
		(property "Datasheet" ""
			(at 175.26 45.72 0)
			(effects
				(font
					(size 1.27 1.27)
				)
				(hide yes)
			)
		)
		(property "Description" ""
			(at 175.26 45.72 0)
			(effects
				(font
					(size 1.27 1.27)
				)
				(hide yes)
			)
		)
		(property "Author" "Antmicro"
			(at 184.15 53.34 0)
			(effects
				(font
					(size 1.27 1.27)
					(thickness 0.15)
				)
				(justify left bottom)
				(hide yes)
			)
		)
		(property "License" "Apache-2.0"
			(at 184.15 55.88 0)
			(effects
				(font
					(size 1.27 1.27)
					(thickness 0.15)
				)
				(justify left bottom)
				(hide yes)
			)
		)
		(pin "1"
		)
		(instances
			(project "artix-dc-scm"
				(path ""
					(reference "#PWR0150")
					(unit 1)
				)
			)
		)
	)
	(symbol
		(lib_id "antmicroResistors0402:R_357k_0402")
		(at 36.83 177.8 270)
		(unit 1)
		(exclude_from_sim no)
		(in_bom yes)
		(on_board yes)
		(dnp no)
		(property "Reference" "R46"
			(at 35.56 177.8 0)
			(effects
				(font
					(size 1.27 1.27)
				)
				(justify right)
			)
		)
		(property "Value" "R_357k_0402"
			(at 33.02 177.8 0)
			(effects
				(font
					(size 1.27 1.27)
				)
				(hide yes)
			)
		)
		(property "Footprint" "antmicro-footprints:R_0402_1005Metric"
			(at 21.59 198.12 0)
			(effects
				(font
					(size 1.27 1.27)
					(thickness 0.15)
				)
				(justify left bottom)
				(hide yes)
			)
		)
		(property "Datasheet" "https://www.bourns.com/docs/product-datasheets/cr.pdf"
			(at 19.05 198.12 0)
			(effects
				(font
					(size 1.27 1.27)
					(thickness 0.15)
				)
				(justify left bottom)
				(hide yes)
			)
		)
		(property "Description" "SMD Chip Resistor"
			(at 36.83 177.8 0)
			(effects
				(font
					(size 1.27 1.27)
				)
				(hide yes)
			)
		)
		(property "Manufacturer" "Bourns"
			(at 13.97 198.12 0)
			(effects
				(font
					(size 1.27 1.27)
					(thickness 0.15)
				)
				(justify left bottom)
				(hide yes)
			)
		)
		(property "MPN" "CR0402-FX-3573GLF"
			(at 16.51 198.12 0)
			(effects
				(font
					(size 1.27 1.27)
					(thickness 0.15)
				)
				(justify left bottom)
				(hide yes)
			)
		)
		(property "Val" "357k"
			(at 35.56 182.88 0)
			(effects
				(font
					(size 1.27 1.27)
					(thickness 0.15)
				)
				(justify left)
			)
		)
		(property "License" "Apache-2.0"
			(at 11.43 198.12 0)
			(effects
				(font
					(size 1.27 1.27)
					(thickness 0.15)
				)
				(justify left bottom)
				(hide yes)
			)
		)
		(property "Author" "Antmicro"
			(at 8.89 198.12 0)
			(effects
				(font
					(size 1.27 1.27)
					(thickness 0.15)
				)
				(justify left bottom)
				(hide yes)
			)
		)
		(property "Tolerance" "1%"
			(at 26.67 198.12 0)
			(effects
				(font
					(size 1.27 1.27)
				)
				(justify left bottom)
				(hide yes)
			)
		)
		(pin "1"
		)
		(pin "2"
		)
		(instances
			(project "artix-dc-scm"
				(path ""
					(reference "R46")
					(unit 1)
				)
			)
		)
	)
	(symbol
		(lib_id "antmicroResistors0402:R_357k_0402")
		(at 40.64 177.8 270)
		(unit 1)
		(exclude_from_sim no)
		(in_bom yes)
		(on_board yes)
		(dnp no)
		(property "Reference" "R45"
			(at 39.37 177.8 0)
			(effects
				(font
					(size 1.27 1.27)
				)
				(justify right)
			)
		)
		(property "Value" "R_357k_0402"
			(at 36.83 177.8 0)
			(effects
				(font
					(size 1.27 1.27)
				)
				(hide yes)
			)
		)
		(property "Footprint" "antmicro-footprints:R_0402_1005Metric"
			(at 25.4 198.12 0)
			(effects
				(font
					(size 1.27 1.27)
					(thickness 0.15)
				)
				(justify left bottom)
				(hide yes)
			)
		)
		(property "Datasheet" "https://www.bourns.com/docs/product-datasheets/cr.pdf"
			(at 22.86 198.12 0)
			(effects
				(font
					(size 1.27 1.27)
					(thickness 0.15)
				)
				(justify left bottom)
				(hide yes)
			)
		)
		(property "Description" "SMD Chip Resistor"
			(at 40.64 177.8 0)
			(effects
				(font
					(size 1.27 1.27)
				)
				(hide yes)
			)
		)
		(property "Manufacturer" "Bourns"
			(at 17.78 198.12 0)
			(effects
				(font
					(size 1.27 1.27)
					(thickness 0.15)
				)
				(justify left bottom)
				(hide yes)
			)
		)
		(property "MPN" "CR0402-FX-3573GLF"
			(at 20.32 198.12 0)
			(effects
				(font
					(size 1.27 1.27)
					(thickness 0.15)
				)
				(justify left bottom)
				(hide yes)
			)
		)
		(property "Val" "357k"
			(at 39.37 187.325 0)
			(effects
				(font
					(size 1.27 1.27)
					(thickness 0.15)
				)
				(justify right)
			)
		)
		(property "License" "Apache-2.0"
			(at 15.24 198.12 0)
			(effects
				(font
					(size 1.27 1.27)
					(thickness 0.15)
				)
				(justify left bottom)
				(hide yes)
			)
		)
		(property "Author" "Antmicro"
			(at 12.7 198.12 0)
			(effects
				(font
					(size 1.27 1.27)
					(thickness 0.15)
				)
				(justify left bottom)
				(hide yes)
			)
		)
		(property "Tolerance" "1%"
			(at 30.48 198.12 0)
			(effects
				(font
					(size 1.27 1.27)
				)
				(justify left bottom)
				(hide yes)
			)
		)
		(pin "1"
		)
		(pin "2"
		)
		(instances
			(project "artix-dc-scm"
				(path ""
					(reference "R45")
					(unit 1)
				)
			)
		)
	)
	(symbol
		(lib_id "antmicroResistors0402:R_357k_0402")
		(at 46.99 177.8 270)
		(unit 1)
		(exclude_from_sim no)
		(in_bom yes)
		(on_board yes)
		(dnp no)
		(property "Reference" "R47"
			(at 45.72 177.8 0)
			(effects
				(font
					(size 1.27 1.27)
				)
				(justify right)
			)
		)
		(property "Value" "R_357k_0402"
			(at 43.18 177.8 0)
			(effects
				(font
					(size 1.27 1.27)
				)
				(hide yes)
			)
		)
		(property "Footprint" "antmicro-footprints:R_0402_1005Metric"
			(at 31.75 198.12 0)
			(effects
				(font
					(size 1.27 1.27)
					(thickness 0.15)
				)
				(justify left bottom)
				(hide yes)
			)
		)
		(property "Datasheet" "https://www.bourns.com/docs/product-datasheets/cr.pdf"
			(at 29.21 198.12 0)
			(effects
				(font
					(size 1.27 1.27)
					(thickness 0.15)
				)
				(justify left bottom)
				(hide yes)
			)
		)
		(property "Description" "SMD Chip Resistor"
			(at 46.99 177.8 0)
			(effects
				(font
					(size 1.27 1.27)
				)
				(hide yes)
			)
		)
		(property "Manufacturer" "Bourns"
			(at 24.13 198.12 0)
			(effects
				(font
					(size 1.27 1.27)
					(thickness 0.15)
				)
				(justify left bottom)
				(hide yes)
			)
		)
		(property "MPN" "CR0402-FX-3573GLF"
			(at 26.67 198.12 0)
			(effects
				(font
					(size 1.27 1.27)
					(thickness 0.15)
				)
				(justify left bottom)
				(hide yes)
			)
		)
		(property "Val" "357k"
			(at 45.72 187.325 0)
			(effects
				(font
					(size 1.27 1.27)
					(thickness 0.15)
				)
				(justify right)
			)
		)
		(property "License" "Apache-2.0"
			(at 21.59 198.12 0)
			(effects
				(font
					(size 1.27 1.27)
					(thickness 0.15)
				)
				(justify left bottom)
				(hide yes)
			)
		)
		(property "Author" "Antmicro"
			(at 19.05 198.12 0)
			(effects
				(font
					(size 1.27 1.27)
					(thickness 0.15)
				)
				(justify left bottom)
				(hide yes)
			)
		)
		(property "Tolerance" "1%"
			(at 36.83 198.12 0)
			(effects
				(font
					(size 1.27 1.27)
				)
				(justify left bottom)
				(hide yes)
			)
		)
		(pin "1"
		)
		(pin "2"
		)
		(instances
			(project "artix-dc-scm"
				(path ""
					(reference "R47")
					(unit 1)
				)
			)
		)
	)
	(symbol
		(lib_id "antmicroResistors0402:R_357k_0402")
		(at 53.34 177.8 270)
		(unit 1)
		(exclude_from_sim no)
		(in_bom yes)
		(on_board yes)
		(dnp no)
		(property "Reference" "R49"
			(at 52.07 173.99 0)
			(effects
				(font
					(size 1.27 1.27)
				)
				(justify left)
			)
		)
		(property "Value" "R_357k_0402"
			(at 49.53 177.8 0)
			(effects
				(font
					(size 1.27 1.27)
				)
				(hide yes)
			)
		)
		(property "Footprint" "antmicro-footprints:R_0402_1005Metric"
			(at 38.1 198.12 0)
			(effects
				(font
					(size 1.27 1.27)
					(thickness 0.15)
				)
				(justify left bottom)
				(hide yes)
			)
		)
		(property "Datasheet" "https://www.bourns.com/docs/product-datasheets/cr.pdf"
			(at 35.56 198.12 0)
			(effects
				(font
					(size 1.27 1.27)
					(thickness 0.15)
				)
				(justify left bottom)
				(hide yes)
			)
		)
		(property "Description" "SMD Chip Resistor"
			(at 53.34 177.8 0)
			(effects
				(font
					(size 1.27 1.27)
				)
				(hide yes)
			)
		)
		(property "Manufacturer" "Bourns"
			(at 30.48 198.12 0)
			(effects
				(font
					(size 1.27 1.27)
					(thickness 0.15)
				)
				(justify left bottom)
				(hide yes)
			)
		)
		(property "MPN" "CR0402-FX-3573GLF"
			(at 33.02 198.12 0)
			(effects
				(font
					(size 1.27 1.27)
					(thickness 0.15)
				)
				(justify left bottom)
				(hide yes)
			)
		)
		(property "Val" "357k"
			(at 52.07 182.88 0)
			(effects
				(font
					(size 1.27 1.27)
					(thickness 0.15)
				)
				(justify left)
			)
		)
		(property "License" "Apache-2.0"
			(at 27.94 198.12 0)
			(effects
				(font
					(size 1.27 1.27)
					(thickness 0.15)
				)
				(justify left bottom)
				(hide yes)
			)
		)
		(property "Author" "Antmicro"
			(at 25.4 198.12 0)
			(effects
				(font
					(size 1.27 1.27)
					(thickness 0.15)
				)
				(justify left bottom)
				(hide yes)
			)
		)
		(property "Tolerance" "1%"
			(at 43.18 198.12 0)
			(effects
				(font
					(size 1.27 1.27)
				)
				(justify left bottom)
				(hide yes)
			)
		)
		(pin "1"
		)
		(pin "2"
		)
		(instances
			(project "artix-dc-scm"
				(path ""
					(reference "R49")
					(unit 1)
				)
			)
		)
	)
	(symbol
		(lib_id "antmicroResistors0402:R_357k_0402")
		(at 49.53 177.8 270)
		(unit 1)
		(exclude_from_sim no)
		(in_bom yes)
		(on_board yes)
		(dnp no)
		(property "Reference" "R50"
			(at 48.26 173.99 0)
			(effects
				(font
					(size 1.27 1.27)
				)
				(justify left)
			)
		)
		(property "Value" "R_357k_0402"
			(at 45.72 177.8 0)
			(effects
				(font
					(size 1.27 1.27)
				)
				(hide yes)
			)
		)
		(property "Footprint" "antmicro-footprints:R_0402_1005Metric"
			(at 34.29 198.12 0)
			(effects
				(font
					(size 1.27 1.27)
					(thickness 0.15)
				)
				(justify left bottom)
				(hide yes)
			)
		)
		(property "Datasheet" "https://www.bourns.com/docs/product-datasheets/cr.pdf"
			(at 31.75 198.12 0)
			(effects
				(font
					(size 1.27 1.27)
					(thickness 0.15)
				)
				(justify left bottom)
				(hide yes)
			)
		)
		(property "Description" "SMD Chip Resistor"
			(at 49.53 177.8 0)
			(effects
				(font
					(size 1.27 1.27)
				)
				(hide yes)
			)
		)
		(property "Manufacturer" "Bourns"
			(at 26.67 198.12 0)
			(effects
				(font
					(size 1.27 1.27)
					(thickness 0.15)
				)
				(justify left bottom)
				(hide yes)
			)
		)
		(property "MPN" "CR0402-FX-3573GLF"
			(at 29.21 198.12 0)
			(effects
				(font
					(size 1.27 1.27)
					(thickness 0.15)
				)
				(justify left bottom)
				(hide yes)
			)
		)
		(property "Val" "357k"
			(at 48.26 182.88 0)
			(effects
				(font
					(size 1.27 1.27)
					(thickness 0.15)
				)
				(justify left)
			)
		)
		(property "License" "Apache-2.0"
			(at 24.13 198.12 0)
			(effects
				(font
					(size 1.27 1.27)
					(thickness 0.15)
				)
				(justify left bottom)
				(hide yes)
			)
		)
		(property "Author" "Antmicro"
			(at 21.59 198.12 0)
			(effects
				(font
					(size 1.27 1.27)
					(thickness 0.15)
				)
				(justify left bottom)
				(hide yes)
			)
		)
		(property "Tolerance" "1%"
			(at 39.37 198.12 0)
			(effects
				(font
					(size 1.27 1.27)
				)
				(justify left bottom)
				(hide yes)
			)
		)
		(pin "1"
		)
		(pin "2"
		)
		(instances
			(project "artix-dc-scm"
				(path ""
					(reference "R50")
					(unit 1)
				)
			)
		)
	)
	(symbol
		(lib_id "antmicroResistors0402:R_357k_0402")
		(at 59.69 177.8 270)
		(unit 1)
		(exclude_from_sim no)
		(in_bom yes)
		(on_board yes)
		(dnp no)
		(property "Reference" "R51"
			(at 58.42 173.99 0)
			(effects
				(font
					(size 1.27 1.27)
				)
				(justify left)
			)
		)
		(property "Value" "R_357k_0402"
			(at 55.88 177.8 0)
			(effects
				(font
					(size 1.27 1.27)
				)
				(hide yes)
			)
		)
		(property "Footprint" "antmicro-footprints:R_0402_1005Metric"
			(at 44.45 198.12 0)
			(effects
				(font
					(size 1.27 1.27)
					(thickness 0.15)
				)
				(justify left bottom)
				(hide yes)
			)
		)
		(property "Datasheet" "https://www.bourns.com/docs/product-datasheets/cr.pdf"
			(at 41.91 198.12 0)
			(effects
				(font
					(size 1.27 1.27)
					(thickness 0.15)
				)
				(justify left bottom)
				(hide yes)
			)
		)
		(property "Description" "SMD Chip Resistor"
			(at 59.69 177.8 0)
			(effects
				(font
					(size 1.27 1.27)
				)
				(hide yes)
			)
		)
		(property "Manufacturer" "Bourns"
			(at 36.83 198.12 0)
			(effects
				(font
					(size 1.27 1.27)
					(thickness 0.15)
				)
				(justify left bottom)
				(hide yes)
			)
		)
		(property "MPN" "CR0402-FX-3573GLF"
			(at 39.37 198.12 0)
			(effects
				(font
					(size 1.27 1.27)
					(thickness 0.15)
				)
				(justify left bottom)
				(hide yes)
			)
		)
		(property "Val" "357k"
			(at 58.42 182.88 0)
			(effects
				(font
					(size 1.27 1.27)
					(thickness 0.15)
				)
				(justify left)
			)
		)
		(property "License" "Apache-2.0"
			(at 34.29 198.12 0)
			(effects
				(font
					(size 1.27 1.27)
					(thickness 0.15)
				)
				(justify left bottom)
				(hide yes)
			)
		)
		(property "Author" "Antmicro"
			(at 31.75 198.12 0)
			(effects
				(font
					(size 1.27 1.27)
					(thickness 0.15)
				)
				(justify left bottom)
				(hide yes)
			)
		)
		(property "Tolerance" "1%"
			(at 49.53 198.12 0)
			(effects
				(font
					(size 1.27 1.27)
				)
				(justify left bottom)
				(hide yes)
			)
		)
		(pin "1"
		)
		(pin "2"
		)
		(instances
			(project "artix-dc-scm"
				(path ""
					(reference "R51")
					(unit 1)
				)
			)
		)
	)
	(symbol
		(lib_id "antmicroResistors0402:R_357k_0402")
		(at 55.88 177.8 270)
		(unit 1)
		(exclude_from_sim no)
		(in_bom yes)
		(on_board yes)
		(dnp no)
		(property "Reference" "R52"
			(at 54.61 173.99 0)
			(effects
				(font
					(size 1.27 1.27)
				)
				(justify left)
			)
		)
		(property "Value" "R_357k_0402"
			(at 52.07 177.8 0)
			(effects
				(font
					(size 1.27 1.27)
				)
				(hide yes)
			)
		)
		(property "Footprint" "antmicro-footprints:R_0402_1005Metric"
			(at 40.64 198.12 0)
			(effects
				(font
					(size 1.27 1.27)
					(thickness 0.15)
				)
				(justify left bottom)
				(hide yes)
			)
		)
		(property "Datasheet" "https://www.bourns.com/docs/product-datasheets/cr.pdf"
			(at 38.1 198.12 0)
			(effects
				(font
					(size 1.27 1.27)
					(thickness 0.15)
				)
				(justify left bottom)
				(hide yes)
			)
		)
		(property "Description" "SMD Chip Resistor"
			(at 55.88 177.8 0)
			(effects
				(font
					(size 1.27 1.27)
				)
				(hide yes)
			)
		)
		(property "Manufacturer" "Bourns"
			(at 33.02 198.12 0)
			(effects
				(font
					(size 1.27 1.27)
					(thickness 0.15)
				)
				(justify left bottom)
				(hide yes)
			)
		)
		(property "MPN" "CR0402-FX-3573GLF"
			(at 35.56 198.12 0)
			(effects
				(font
					(size 1.27 1.27)
					(thickness 0.15)
				)
				(justify left bottom)
				(hide yes)
			)
		)
		(property "Val" "357k"
			(at 54.61 182.88 0)
			(effects
				(font
					(size 1.27 1.27)
					(thickness 0.15)
				)
				(justify left)
			)
		)
		(property "License" "Apache-2.0"
			(at 30.48 198.12 0)
			(effects
				(font
					(size 1.27 1.27)
					(thickness 0.15)
				)
				(justify left bottom)
				(hide yes)
			)
		)
		(property "Author" "Antmicro"
			(at 27.94 198.12 0)
			(effects
				(font
					(size 1.27 1.27)
					(thickness 0.15)
				)
				(justify left bottom)
				(hide yes)
			)
		)
		(property "Tolerance" "1%"
			(at 45.72 198.12 0)
			(effects
				(font
					(size 1.27 1.27)
				)
				(justify left bottom)
				(hide yes)
			)
		)
		(pin "1"
		)
		(pin "2"
		)
		(instances
			(project "artix-dc-scm"
				(path ""
					(reference "R52")
					(unit 1)
				)
			)
		)
	)
	(symbol
		(lib_id "antmicroResistors0402:R_200k_0402")
		(at 77.47 172.72 0)
		(mirror x)
		(unit 1)
		(exclude_from_sim no)
		(in_bom yes)
		(on_board yes)
		(dnp no)
		(property "Reference" "R53"
			(at 80.01 167.64 0)
			(effects
				(font
					(size 1.27 1.27)
				)
			)
		)
		(property "Value" "R_200k_0402"
			(at 77.47 168.91 0)
			(effects
				(font
					(size 1.27 1.27)
				)
				(hide yes)
			)
		)
		(property "Footprint" "antmicro-footprints:R_0402_1005Metric"
			(at 97.79 157.48 0)
			(effects
				(font
					(size 1.27 1.27)
					(thickness 0.15)
				)
				(justify left bottom)
				(hide yes)
			)
		)
		(property "Datasheet" "https://www.bourns.com/docs/product-datasheets/cr.pdf"
			(at 97.79 154.94 0)
			(effects
				(font
					(size 1.27 1.27)
					(thickness 0.15)
				)
				(justify left bottom)
				(hide yes)
			)
		)
		(property "Description" "SMD Chip Resistor, 200 kohm, ± 1%, 62.5 mW, 0402 [1005 Metric], Thick Film, General Purpose"
			(at 77.47 172.72 0)
			(effects
				(font
					(size 1.27 1.27)
				)
				(hide yes)
			)
		)
		(property "Manufacturer" "Bourns"
			(at 97.79 149.86 0)
			(effects
				(font
					(size 1.27 1.27)
					(thickness 0.15)
				)
				(justify left bottom)
				(hide yes)
			)
		)
		(property "MPN" "CR0402-FX-2003GLF"
			(at 97.79 152.4 0)
			(effects
				(font
					(size 1.27 1.27)
					(thickness 0.15)
				)
				(justify left bottom)
				(hide yes)
			)
		)
		(property "Val" "200k"
			(at 80.01 170.18 0)
			(effects
				(font
					(size 1.27 1.27)
					(thickness 0.15)
				)
			)
		)
		(property "License" "Apache-2.0"
			(at 97.79 147.32 0)
			(effects
				(font
					(size 1.27 1.27)
					(thickness 0.15)
				)
				(justify left bottom)
				(hide yes)
			)
		)
		(property "Author" "Antmicro"
			(at 97.79 144.78 0)
			(effects
				(font
					(size 1.27 1.27)
					(thickness 0.15)
				)
				(justify left bottom)
				(hide yes)
			)
		)
		(property "Tolerance" "1%"
			(at 97.79 162.56 0)
			(effects
				(font
					(size 1.27 1.27)
				)
				(justify left bottom)
				(hide yes)
			)
		)
		(pin "1"
		)
		(pin "2"
		)
		(instances
			(project "artix-dc-scm"
				(path ""
					(reference "R53")
					(unit 1)
				)
			)
		)
	)
	(symbol
		(lib_id "antmicroCapacitorsmisc:C_100n_6V3_0402")
		(at 86.36 179.07 270)
		(mirror x)
		(unit 1)
		(exclude_from_sim no)
		(in_bom yes)
		(on_board yes)
		(dnp no)
		(property "Reference" "C39"
			(at 86.995 174.625 90)
			(effects
				(font
					(size 1.27 1.27)
				)
				(justify left)
			)
		)
		(property "Value" "C_100n_6V3_0402"
			(at 76.2 158.75 0)
			(effects
				(font
					(size 1.27 1.27)
					(thickness 0.15)
				)
				(justify left bottom)
				(hide yes)
			)
		)
		(property "Footprint" "antmicro-footprints:C_0402_1005Metric"
			(at 73.66 158.75 0)
			(effects
				(font
					(size 1.27 1.27)
					(thickness 0.15)
				)
				(justify left bottom)
				(hide yes)
			)
		)
		(property "Datasheet" "https://www.passivecomponent.com/wp-content/uploads/datasheet/WTC_MLCC_General_Purpose.pdf"
			(at 71.12 158.75 0)
			(effects
				(font
					(size 1.27 1.27)
					(thickness 0.15)
				)
				(justify left bottom)
				(hide yes)
			)
		)
		(property "Description" "SMT Multilayer Ceramic Capacitor, 0.1 µF, 6.3 V, 0402 [1005 Metric], ± 10%, X5R, Walsin MLCC"
			(at 86.36 179.07 0)
			(effects
				(font
					(size 1.27 1.27)
				)
				(hide yes)
			)
		)
		(property "Manufacturer" "Walsin"
			(at 66.04 158.75 0)
			(effects
				(font
					(size 1.27 1.27)
					(thickness 0.15)
				)
				(justify left bottom)
				(hide yes)
			)
		)
		(property "MPN" "0402X104K6R3CT"
			(at 68.58 158.75 0)
			(effects
				(font
					(size 1.27 1.27)
					(thickness 0.15)
				)
				(justify left bottom)
				(hide yes)
			)
		)
		(property "Val" "100n"
			(at 86.995 178.435 90)
			(effects
				(font
					(size 1.27 1.27)
					(thickness 0.15)
				)
				(justify left)
			)
		)
		(property "License" "Apache-2.0"
			(at 63.5 158.75 0)
			(effects
				(font
					(size 1.27 1.27)
					(thickness 0.15)
				)
				(justify left bottom)
				(hide yes)
			)
		)
		(property "Author" "Antmicro"
			(at 60.96 158.75 0)
			(effects
				(font
					(size 1.27 1.27)
					(thickness 0.15)
				)
				(justify left bottom)
				(hide yes)
			)
		)
		(property "Voltage" ""
			(at 58.42 158.75 0)
			(effects
				(font
					(size 1.27 1.27)
				)
				(justify left bottom)
				(hide yes)
			)
		)
		(property "Dielectric" ""
			(at 55.88 158.75 0)
			(effects
				(font
					(size 1.27 1.27)
				)
				(justify left bottom)
				(hide yes)
			)
		)
		(property "Public" "False"
			(at 53.34 158.75 0)
			(effects
				(font
					(size 1.27 1.27)
				)
				(justify left bottom)
				(hide yes)
			)
		)
		(pin "1"
		)
		(pin "2"
		)
		(instances
			(project "artix-dc-scm"
				(path ""
					(reference "C39")
					(unit 1)
				)
			)
		)
	)
	(symbol
		(lib_id "antmicropower:GND")
		(at 86.36 179.07 0)
		(unit 1)
		(exclude_from_sim no)
		(in_bom yes)
		(on_board yes)
		(dnp no)
		(property "Reference" "#PWR034"
			(at 86.36 185.42 0)
			(effects
				(font
					(size 1.27 1.27)
				)
				(hide yes)
			)
		)
		(property "Value" "GND"
			(at 86.36 182.88 0)
			(effects
				(font
					(size 1.27 1.27)
				)
			)
		)
		(property "Footprint" ""
			(at 86.36 179.07 0)
			(effects
				(font
					(size 1.27 1.27)
				)
				(hide yes)
			)
		)
		(property "Datasheet" ""
			(at 86.36 179.07 0)
			(effects
				(font
					(size 1.27 1.27)
				)
				(hide yes)
			)
		)
		(property "Description" ""
			(at 86.36 179.07 0)
			(effects
				(font
					(size 1.27 1.27)
				)
				(hide yes)
			)
		)
		(property "Author" "Antmicro"
			(at 95.25 186.69 0)
			(effects
				(font
					(size 1.27 1.27)
					(thickness 0.15)
				)
				(justify left bottom)
				(hide yes)
			)
		)
		(property "License" "Apache-2.0"
			(at 95.25 189.23 0)
			(effects
				(font
					(size 1.27 1.27)
					(thickness 0.15)
				)
				(justify left bottom)
				(hide yes)
			)
		)
		(pin "1"
		)
		(instances
			(project "artix-dc-scm"
				(path ""
					(reference "#PWR034")
					(unit 1)
				)
			)
		)
	)
	(symbol
		(lib_id "antmicroCapacitors0402:C_100n_0402")
		(at 147.32 62.23 90)
		(unit 1)
		(exclude_from_sim no)
		(in_bom yes)
		(on_board yes)
		(dnp no)
		(property "Reference" "C6"
			(at 147.955 57.785 90)
			(effects
				(font
					(size 1.27 1.27)
				)
				(justify right)
			)
		)
		(property "Value" "C_100n_0402"
			(at 157.48 41.91 0)
			(effects
				(font
					(size 1.27 1.27)
					(thickness 0.15)
				)
				(justify left bottom)
				(hide yes)
			)
		)
		(property "Footprint" "antmicro-footprints:C_0402_1005Metric"
			(at 160.02 41.91 0)
			(effects
				(font
					(size 1.27 1.27)
					(thickness 0.15)
				)
				(justify left bottom)
				(hide yes)
			)
		)
		(property "Datasheet" "https://www.murata.com/products/productdetail?partno=GRM155R61H104KE14%23"
			(at 162.56 41.91 0)
			(effects
				(font
					(size 1.27 1.27)
					(thickness 0.15)
				)
				(justify left bottom)
				(hide yes)
			)
		)
		(property "Description" "SMD Multilayer Ceramic Capacitor, 0.1 µF, 50 V, 0402 [1005 Metric], ± 10%, X5R, GRM Series"
			(at 147.32 62.23 0)
			(effects
				(font
					(size 1.27 1.27)
				)
				(hide yes)
			)
		)
		(property "Manufacturer" "Murata"
			(at 167.64 41.91 0)
			(effects
				(font
					(size 1.27 1.27)
					(thickness 0.15)
				)
				(justify left bottom)
				(hide yes)
			)
		)
		(property "MPN" "GRM155R61H104KE14D"
			(at 165.1 41.91 0)
			(effects
				(font
					(size 1.27 1.27)
					(thickness 0.15)
				)
				(justify left bottom)
				(hide yes)
			)
		)
		(property "Val" "100n"
			(at 147.955 61.595 90)
			(effects
				(font
					(size 1.27 1.27)
					(thickness 0.15)
				)
				(justify right)
			)
		)
		(property "License" "Apache-2.0"
			(at 170.18 41.91 0)
			(effects
				(font
					(size 1.27 1.27)
					(thickness 0.15)
				)
				(justify left bottom)
				(hide yes)
			)
		)
		(property "Author" "Antmicro"
			(at 172.72 41.91 0)
			(effects
				(font
					(size 1.27 1.27)
					(thickness 0.15)
				)
				(justify left bottom)
				(hide yes)
			)
		)
		(property "Voltage" "50V"
			(at 175.26 41.91 0)
			(effects
				(font
					(size 1.27 1.27)
				)
				(justify left bottom)
				(hide yes)
			)
		)
		(property "Dielectric" "X5R"
			(at 177.8 41.91 0)
			(effects
				(font
					(size 1.27 1.27)
				)
				(justify left bottom)
				(hide yes)
			)
		)
		(pin "1"
		)
		(pin "2"
		)
		(instances
			(project "artix-dc-scm"
				(path ""
					(reference "C6")
					(unit 1)
				)
			)
		)
	)
	(symbol
		(lib_id "antmicroCapacitors0402:C_100n_0402")
		(at 153.67 62.23 90)
		(unit 1)
		(exclude_from_sim no)
		(in_bom yes)
		(on_board yes)
		(dnp no)
		(property "Reference" "C7"
			(at 154.305 57.785 90)
			(effects
				(font
					(size 1.27 1.27)
				)
				(justify right)
			)
		)
		(property "Value" "C_100n_0402"
			(at 163.83 41.91 0)
			(effects
				(font
					(size 1.27 1.27)
					(thickness 0.15)
				)
				(justify left bottom)
				(hide yes)
			)
		)
		(property "Footprint" "antmicro-footprints:C_0402_1005Metric"
			(at 166.37 41.91 0)
			(effects
				(font
					(size 1.27 1.27)
					(thickness 0.15)
				)
				(justify left bottom)
				(hide yes)
			)
		)
		(property "Datasheet" "https://www.murata.com/products/productdetail?partno=GRM155R61H104KE14%23"
			(at 168.91 41.91 0)
			(effects
				(font
					(size 1.27 1.27)
					(thickness 0.15)
				)
				(justify left bottom)
				(hide yes)
			)
		)
		(property "Description" "SMD Multilayer Ceramic Capacitor, 0.1 µF, 50 V, 0402 [1005 Metric], ± 10%, X5R, GRM Series"
			(at 153.67 62.23 0)
			(effects
				(font
					(size 1.27 1.27)
				)
				(hide yes)
			)
		)
		(property "Manufacturer" "Murata"
			(at 173.99 41.91 0)
			(effects
				(font
					(size 1.27 1.27)
					(thickness 0.15)
				)
				(justify left bottom)
				(hide yes)
			)
		)
		(property "MPN" "GRM155R61H104KE14D"
			(at 171.45 41.91 0)
			(effects
				(font
					(size 1.27 1.27)
					(thickness 0.15)
				)
				(justify left bottom)
				(hide yes)
			)
		)
		(property "Val" "100n"
			(at 154.305 61.595 90)
			(effects
				(font
					(size 1.27 1.27)
					(thickness 0.15)
				)
				(justify right)
			)
		)
		(property "License" "Apache-2.0"
			(at 176.53 41.91 0)
			(effects
				(font
					(size 1.27 1.27)
					(thickness 0.15)
				)
				(justify left bottom)
				(hide yes)
			)
		)
		(property "Author" "Antmicro"
			(at 179.07 41.91 0)
			(effects
				(font
					(size 1.27 1.27)
					(thickness 0.15)
				)
				(justify left bottom)
				(hide yes)
			)
		)
		(property "Voltage" "50V"
			(at 181.61 41.91 0)
			(effects
				(font
					(size 1.27 1.27)
				)
				(justify left bottom)
				(hide yes)
			)
		)
		(property "Dielectric" "X5R"
			(at 184.15 41.91 0)
			(effects
				(font
					(size 1.27 1.27)
				)
				(justify left bottom)
				(hide yes)
			)
		)
		(pin "1"
		)
		(pin "2"
		)
		(instances
			(project "artix-dc-scm"
				(path ""
					(reference "C7")
					(unit 1)
				)
			)
		)
	)
	(symbol
		(lib_id "antmicroCapacitors0402:C_100n_0402")
		(at 161.29 62.23 90)
		(unit 1)
		(exclude_from_sim no)
		(in_bom yes)
		(on_board yes)
		(dnp no)
		(property "Reference" "C107"
			(at 161.925 57.785 90)
			(effects
				(font
					(size 1.27 1.27)
				)
				(justify right)
			)
		)
		(property "Value" "C_100n_0402"
			(at 171.45 41.91 0)
			(effects
				(font
					(size 1.27 1.27)
					(thickness 0.15)
				)
				(justify left bottom)
				(hide yes)
			)
		)
		(property "Footprint" "antmicro-footprints:C_0402_1005Metric"
			(at 173.99 41.91 0)
			(effects
				(font
					(size 1.27 1.27)
					(thickness 0.15)
				)
				(justify left bottom)
				(hide yes)
			)
		)
		(property "Datasheet" "https://www.murata.com/products/productdetail?partno=GRM155R61H104KE14%23"
			(at 176.53 41.91 0)
			(effects
				(font
					(size 1.27 1.27)
					(thickness 0.15)
				)
				(justify left bottom)
				(hide yes)
			)
		)
		(property "Description" "SMD Multilayer Ceramic Capacitor, 0.1 µF, 50 V, 0402 [1005 Metric], ± 10%, X5R, GRM Series"
			(at 161.29 62.23 0)
			(effects
				(font
					(size 1.27 1.27)
				)
				(hide yes)
			)
		)
		(property "Manufacturer" "Murata"
			(at 181.61 41.91 0)
			(effects
				(font
					(size 1.27 1.27)
					(thickness 0.15)
				)
				(justify left bottom)
				(hide yes)
			)
		)
		(property "MPN" "GRM155R61H104KE14D"
			(at 179.07 41.91 0)
			(effects
				(font
					(size 1.27 1.27)
					(thickness 0.15)
				)
				(justify left bottom)
				(hide yes)
			)
		)
		(property "Val" "100n"
			(at 161.925 61.595 90)
			(effects
				(font
					(size 1.27 1.27)
					(thickness 0.15)
				)
				(justify right)
			)
		)
		(property "License" "Apache-2.0"
			(at 184.15 41.91 0)
			(effects
				(font
					(size 1.27 1.27)
					(thickness 0.15)
				)
				(justify left bottom)
				(hide yes)
			)
		)
		(property "Author" "Antmicro"
			(at 186.69 41.91 0)
			(effects
				(font
					(size 1.27 1.27)
					(thickness 0.15)
				)
				(justify left bottom)
				(hide yes)
			)
		)
		(property "Voltage" "50V"
			(at 189.23 41.91 0)
			(effects
				(font
					(size 1.27 1.27)
				)
				(justify left bottom)
				(hide yes)
			)
		)
		(property "Dielectric" "X5R"
			(at 191.77 41.91 0)
			(effects
				(font
					(size 1.27 1.27)
				)
				(justify left bottom)
				(hide yes)
			)
		)
		(pin "1"
		)
		(pin "2"
		)
		(instances
			(project "artix-dc-scm"
				(path ""
					(reference "C107")
					(unit 1)
				)
			)
		)
	)
	(symbol
		(lib_id "antmicroCapacitors0402:C_100n_0402")
		(at 167.64 62.23 90)
		(unit 1)
		(exclude_from_sim no)
		(in_bom yes)
		(on_board yes)
		(dnp no)
		(property "Reference" "C135"
			(at 168.275 57.785 90)
			(effects
				(font
					(size 1.27 1.27)
				)
				(justify right)
			)
		)
		(property "Value" "C_100n_0402"
			(at 177.8 41.91 0)
			(effects
				(font
					(size 1.27 1.27)
					(thickness 0.15)
				)
				(justify left bottom)
				(hide yes)
			)
		)
		(property "Footprint" "antmicro-footprints:C_0402_1005Metric"
			(at 180.34 41.91 0)
			(effects
				(font
					(size 1.27 1.27)
					(thickness 0.15)
				)
				(justify left bottom)
				(hide yes)
			)
		)
		(property "Datasheet" "https://www.murata.com/products/productdetail?partno=GRM155R61H104KE14%23"
			(at 182.88 41.91 0)
			(effects
				(font
					(size 1.27 1.27)
					(thickness 0.15)
				)
				(justify left bottom)
				(hide yes)
			)
		)
		(property "Description" "SMD Multilayer Ceramic Capacitor, 0.1 µF, 50 V, 0402 [1005 Metric], ± 10%, X5R, GRM Series"
			(at 167.64 62.23 0)
			(effects
				(font
					(size 1.27 1.27)
				)
				(hide yes)
			)
		)
		(property "Manufacturer" "Murata"
			(at 187.96 41.91 0)
			(effects
				(font
					(size 1.27 1.27)
					(thickness 0.15)
				)
				(justify left bottom)
				(hide yes)
			)
		)
		(property "MPN" "GRM155R61H104KE14D"
			(at 185.42 41.91 0)
			(effects
				(font
					(size 1.27 1.27)
					(thickness 0.15)
				)
				(justify left bottom)
				(hide yes)
			)
		)
		(property "Val" "100n"
			(at 168.275 61.595 90)
			(effects
				(font
					(size 1.27 1.27)
					(thickness 0.15)
				)
				(justify right)
			)
		)
		(property "License" "Apache-2.0"
			(at 190.5 41.91 0)
			(effects
				(font
					(size 1.27 1.27)
					(thickness 0.15)
				)
				(justify left bottom)
				(hide yes)
			)
		)
		(property "Author" "Antmicro"
			(at 193.04 41.91 0)
			(effects
				(font
					(size 1.27 1.27)
					(thickness 0.15)
				)
				(justify left bottom)
				(hide yes)
			)
		)
		(property "Voltage" "50V"
			(at 195.58 41.91 0)
			(effects
				(font
					(size 1.27 1.27)
				)
				(justify left bottom)
				(hide yes)
			)
		)
		(property "Dielectric" "X5R"
			(at 198.12 41.91 0)
			(effects
				(font
					(size 1.27 1.27)
				)
				(justify left bottom)
				(hide yes)
			)
		)
		(pin "1"
		)
		(pin "2"
		)
		(instances
			(project "artix-dc-scm"
				(path ""
					(reference "C135")
					(unit 1)
				)
			)
		)
	)
	(symbol
		(lib_id "antmicropower:GND")
		(at 167.64 62.23 0)
		(unit 1)
		(exclude_from_sim no)
		(in_bom yes)
		(on_board yes)
		(dnp no)
		(property "Reference" "#PWR0134"
			(at 167.64 68.58 0)
			(effects
				(font
					(size 1.27 1.27)
				)
				(hide yes)
			)
		)
		(property "Value" "GND"
			(at 167.64 66.04 0)
			(effects
				(font
					(size 1.27 1.27)
				)
			)
		)
		(property "Footprint" ""
			(at 167.64 62.23 0)
			(effects
				(font
					(size 1.27 1.27)
				)
				(hide yes)
			)
		)
		(property "Datasheet" ""
			(at 167.64 62.23 0)
			(effects
				(font
					(size 1.27 1.27)
				)
				(hide yes)
			)
		)
		(property "Description" ""
			(at 167.64 62.23 0)
			(effects
				(font
					(size 1.27 1.27)
				)
				(hide yes)
			)
		)
		(property "Author" "Antmicro"
			(at 176.53 69.85 0)
			(effects
				(font
					(size 1.27 1.27)
					(thickness 0.15)
				)
				(justify left bottom)
				(hide yes)
			)
		)
		(property "License" "Apache-2.0"
			(at 176.53 72.39 0)
			(effects
				(font
					(size 1.27 1.27)
					(thickness 0.15)
				)
				(justify left bottom)
				(hide yes)
			)
		)
		(pin "1"
		)
		(instances
			(project "artix-dc-scm"
				(path ""
					(reference "#PWR0134")
					(unit 1)
				)
			)
		)
	)
	(symbol
		(lib_id "antmicropower:GND")
		(at 161.29 62.23 0)
		(unit 1)
		(exclude_from_sim no)
		(in_bom yes)
		(on_board yes)
		(dnp no)
		(property "Reference" "#PWR0133"
			(at 161.29 68.58 0)
			(effects
				(font
					(size 1.27 1.27)
				)
				(hide yes)
			)
		)
		(property "Value" "GND"
			(at 161.29 66.04 0)
			(effects
				(font
					(size 1.27 1.27)
				)
			)
		)
		(property "Footprint" ""
			(at 161.29 62.23 0)
			(effects
				(font
					(size 1.27 1.27)
				)
				(hide yes)
			)
		)
		(property "Datasheet" ""
			(at 161.29 62.23 0)
			(effects
				(font
					(size 1.27 1.27)
				)
				(hide yes)
			)
		)
		(property "Description" ""
			(at 161.29 62.23 0)
			(effects
				(font
					(size 1.27 1.27)
				)
				(hide yes)
			)
		)
		(property "Author" "Antmicro"
			(at 170.18 69.85 0)
			(effects
				(font
					(size 1.27 1.27)
					(thickness 0.15)
				)
				(justify left bottom)
				(hide yes)
			)
		)
		(property "License" "Apache-2.0"
			(at 170.18 72.39 0)
			(effects
				(font
					(size 1.27 1.27)
					(thickness 0.15)
				)
				(justify left bottom)
				(hide yes)
			)
		)
		(pin "1"
		)
		(instances
			(project "artix-dc-scm"
				(path ""
					(reference "#PWR0133")
					(unit 1)
				)
			)
		)
	)
	(symbol
		(lib_id "antmicropower:GND")
		(at 153.67 62.23 0)
		(unit 1)
		(exclude_from_sim no)
		(in_bom yes)
		(on_board yes)
		(dnp no)
		(property "Reference" "#PWR0132"
			(at 153.67 68.58 0)
			(effects
				(font
					(size 1.27 1.27)
				)
				(hide yes)
			)
		)
		(property "Value" "GND"
			(at 153.67 66.04 0)
			(effects
				(font
					(size 1.27 1.27)
				)
			)
		)
		(property "Footprint" ""
			(at 153.67 62.23 0)
			(effects
				(font
					(size 1.27 1.27)
				)
				(hide yes)
			)
		)
		(property "Datasheet" ""
			(at 153.67 62.23 0)
			(effects
				(font
					(size 1.27 1.27)
				)
				(hide yes)
			)
		)
		(property "Description" ""
			(at 153.67 62.23 0)
			(effects
				(font
					(size 1.27 1.27)
				)
				(hide yes)
			)
		)
		(property "Author" "Antmicro"
			(at 162.56 69.85 0)
			(effects
				(font
					(size 1.27 1.27)
					(thickness 0.15)
				)
				(justify left bottom)
				(hide yes)
			)
		)
		(property "License" "Apache-2.0"
			(at 162.56 72.39 0)
			(effects
				(font
					(size 1.27 1.27)
					(thickness 0.15)
				)
				(justify left bottom)
				(hide yes)
			)
		)
		(pin "1"
		)
		(instances
			(project "artix-dc-scm"
				(path ""
					(reference "#PWR0132")
					(unit 1)
				)
			)
		)
	)
	(symbol
		(lib_id "antmicropower:GND")
		(at 147.32 62.23 0)
		(unit 1)
		(exclude_from_sim no)
		(in_bom yes)
		(on_board yes)
		(dnp no)
		(property "Reference" "#PWR0131"
			(at 147.32 68.58 0)
			(effects
				(font
					(size 1.27 1.27)
				)
				(hide yes)
			)
		)
		(property "Value" "GND"
			(at 147.32 66.04 0)
			(effects
				(font
					(size 1.27 1.27)
				)
			)
		)
		(property "Footprint" ""
			(at 147.32 62.23 0)
			(effects
				(font
					(size 1.27 1.27)
				)
				(hide yes)
			)
		)
		(property "Datasheet" ""
			(at 147.32 62.23 0)
			(effects
				(font
					(size 1.27 1.27)
				)
				(hide yes)
			)
		)
		(property "Description" ""
			(at 147.32 62.23 0)
			(effects
				(font
					(size 1.27 1.27)
				)
				(hide yes)
			)
		)
		(property "Author" "Antmicro"
			(at 156.21 69.85 0)
			(effects
				(font
					(size 1.27 1.27)
					(thickness 0.15)
				)
				(justify left bottom)
				(hide yes)
			)
		)
		(property "License" "Apache-2.0"
			(at 156.21 72.39 0)
			(effects
				(font
					(size 1.27 1.27)
					(thickness 0.15)
				)
				(justify left bottom)
				(hide yes)
			)
		)
		(pin "1"
		)
		(instances
			(project "artix-dc-scm"
				(path ""
					(reference "#PWR0131")
					(unit 1)
				)
			)
		)
	)
	(symbol
		(lib_id "antmicroResistors0402:R_22R_0402")
		(at 261.62 86.36 0)
		(unit 1)
		(exclude_from_sim no)
		(in_bom yes)
		(on_board yes)
		(dnp no)
		(property "Reference" "R195"
			(at 269.24 85.09 0)
			(effects
				(font
					(size 1.27 1.27)
				)
			)
		)
		(property "Value" "R_22R_0402"
			(at 281.94 99.06 0)
			(effects
				(font
					(size 1.27 1.27)
					(thickness 0.15)
				)
				(justify left bottom)
				(hide yes)
			)
		)
		(property "Footprint" "antmicro-footprints:R_0402_1005Metric"
			(at 281.94 101.6 0)
			(effects
				(font
					(size 1.27 1.27)
					(thickness 0.15)
				)
				(justify left bottom)
				(hide yes)
			)
		)
		(property "Datasheet" "https://www.bourns.com/docs/product-datasheets/cr.pdf"
			(at 281.94 104.14 0)
			(effects
				(font
					(size 1.27 1.27)
					(thickness 0.15)
				)
				(justify left bottom)
				(hide yes)
			)
		)
		(property "Description" "SMD Chip Resistor, 22 ohm, ± 1%, 62.5 mW, 0402 [1005 Metric], Thick Film, General Purpose"
			(at 261.62 86.36 0)
			(effects
				(font
					(size 1.27 1.27)
				)
				(hide yes)
			)
		)
		(property "Manufacturer" "Bourns"
			(at 281.94 109.22 0)
			(effects
				(font
					(size 1.27 1.27)
					(thickness 0.15)
				)
				(justify left bottom)
				(hide yes)
			)
		)
		(property "MPN" "CR0402-FX-22R0GLF"
			(at 281.94 106.68 0)
			(effects
				(font
					(size 1.27 1.27)
					(thickness 0.15)
				)
				(justify left bottom)
				(hide yes)
			)
		)
		(property "Val" "22R"
			(at 257.81 86.36 0)
			(effects
				(font
					(size 1.27 1.27)
					(thickness 0.15)
				)
				(justify left bottom)
			)
		)
		(property "License" "Apache-2.0"
			(at 281.94 111.76 0)
			(effects
				(font
					(size 1.27 1.27)
					(thickness 0.15)
				)
				(justify left bottom)
				(hide yes)
			)
		)
		(property "Author" "Antmicro"
			(at 281.94 114.3 0)
			(effects
				(font
					(size 1.27 1.27)
					(thickness 0.15)
				)
				(justify left bottom)
				(hide yes)
			)
		)
		(property "Tolerance" "1%"
			(at 281.94 96.52 0)
			(effects
				(font
					(size 1.27 1.27)
				)
				(justify left bottom)
				(hide yes)
			)
		)
		(pin "1"
		)
		(pin "2"
		)
		(instances
			(project "artix-dc-scm"
				(path ""
					(reference "R195")
					(unit 1)
				)
			)
		)
	)
	(symbol
		(lib_id "antmicroResistors0402:R_22R_0402")
		(at 261.62 88.9 0)
		(unit 1)
		(exclude_from_sim no)
		(in_bom yes)
		(on_board yes)
		(dnp no)
		(property "Reference" "R196"
			(at 269.24 87.63 0)
			(effects
				(font
					(size 1.27 1.27)
				)
			)
		)
		(property "Value" "R_22R_0402"
			(at 281.94 101.6 0)
			(effects
				(font
					(size 1.27 1.27)
					(thickness 0.15)
				)
				(justify left bottom)
				(hide yes)
			)
		)
		(property "Footprint" "antmicro-footprints:R_0402_1005Metric"
			(at 281.94 104.14 0)
			(effects
				(font
					(size 1.27 1.27)
					(thickness 0.15)
				)
				(justify left bottom)
				(hide yes)
			)
		)
		(property "Datasheet" "https://www.bourns.com/docs/product-datasheets/cr.pdf"
			(at 281.94 106.68 0)
			(effects
				(font
					(size 1.27 1.27)
					(thickness 0.15)
				)
				(justify left bottom)
				(hide yes)
			)
		)
		(property "Description" "SMD Chip Resistor, 22 ohm, ± 1%, 62.5 mW, 0402 [1005 Metric], Thick Film, General Purpose"
			(at 261.62 88.9 0)
			(effects
				(font
					(size 1.27 1.27)
				)
				(hide yes)
			)
		)
		(property "Manufacturer" "Bourns"
			(at 281.94 111.76 0)
			(effects
				(font
					(size 1.27 1.27)
					(thickness 0.15)
				)
				(justify left bottom)
				(hide yes)
			)
		)
		(property "MPN" "CR0402-FX-22R0GLF"
			(at 281.94 109.22 0)
			(effects
				(font
					(size 1.27 1.27)
					(thickness 0.15)
				)
				(justify left bottom)
				(hide yes)
			)
		)
		(property "Val" "22R"
			(at 257.81 88.9 0)
			(effects
				(font
					(size 1.27 1.27)
					(thickness 0.15)
				)
				(justify left bottom)
			)
		)
		(property "License" "Apache-2.0"
			(at 281.94 114.3 0)
			(effects
				(font
					(size 1.27 1.27)
					(thickness 0.15)
				)
				(justify left bottom)
				(hide yes)
			)
		)
		(property "Author" "Antmicro"
			(at 281.94 116.84 0)
			(effects
				(font
					(size 1.27 1.27)
					(thickness 0.15)
				)
				(justify left bottom)
				(hide yes)
			)
		)
		(property "Tolerance" "1%"
			(at 281.94 99.06 0)
			(effects
				(font
					(size 1.27 1.27)
				)
				(justify left bottom)
				(hide yes)
			)
		)
		(pin "1"
		)
		(pin "2"
		)
		(instances
			(project "artix-dc-scm"
				(path ""
					(reference "R196")
					(unit 1)
				)
			)
		)
	)
	(symbol
		(lib_id "antmicroLogicTranslatorsLevelShifters:NVT2008BQ,115")
		(at 115.57 182.88 0)
		(mirror y)
		(unit 1)
		(exclude_from_sim no)
		(in_bom yes)
		(on_board yes)
		(dnp no)
		(property "Reference" "U6"
			(at 105.41 175.895 0)
			(effects
				(font
					(size 1.27 1.27)
				)
			)
		)
		(property "Value" "NVT2008BQ,115"
			(at 105.41 178.435 0)
			(effects
				(font
					(size 1.27 1.27)
				)
			)
		)
		(property "Footprint" "antmicro-footprints:VQFN-20_1EP_4.5x2.5mm_P0.5mm"
			(at 80.01 190.5 0)
			(effects
				(font
					(size 1.27 1.27)
					(thickness 0.15)
				)
				(justify left bottom)
				(hide yes)
			)
		)
		(property "Datasheet" "https://www.nxp.com/docs/en/data-sheet/NVT2008_NVT2010.pdf"
			(at 80.01 193.04 0)
			(effects
				(font
					(size 1.27 1.27)
					(thickness 0.15)
				)
				(justify left bottom)
				(hide yes)
			)
		)
		(property "Description" "Bidirectional Voltage Level Translator, 8 Inputs, 1.5ns, 1.8V to 5.5V, DHVQFN-20"
			(at 115.57 182.88 0)
			(effects
				(font
					(size 1.27 1.27)
				)
				(hide yes)
			)
		)
		(property "MPN" "NVT2008BQ,115"
			(at 80.01 195.58 0)
			(effects
				(font
					(size 1.27 1.27)
					(thickness 0.15)
				)
				(justify left bottom)
				(hide yes)
			)
		)
		(property "Manufacturer" "NXP"
			(at 80.01 198.12 0)
			(effects
				(font
					(size 1.27 1.27)
					(thickness 0.15)
				)
				(justify left bottom)
				(hide yes)
			)
		)
		(property "Author" "Antmicro"
			(at 80.01 200.66 0)
			(effects
				(font
					(size 1.27 1.27)
					(thickness 0.15)
				)
				(justify left bottom)
				(hide yes)
			)
		)
		(property "License" "Apache-2.0"
			(at 80.01 203.2 0)
			(effects
				(font
					(size 1.27 1.27)
					(thickness 0.15)
				)
				(justify left bottom)
				(hide yes)
			)
		)
		(pin "1"
		)
		(pin "10"
		)
		(pin "11"
		)
		(pin "12"
		)
		(pin "13"
		)
		(pin "14"
		)
		(pin "15"
		)
		(pin "16"
		)
		(pin "17"
		)
		(pin "18"
		)
		(pin "19"
		)
		(pin "2"
		)
		(pin "20"
		)
		(pin "21"
		)
		(pin "3"
		)
		(pin "4"
		)
		(pin "5"
		)
		(pin "6"
		)
		(pin "7"
		)
		(pin "8"
		)
		(pin "9"
		)
		(instances
			(project "artix-dc-scm"
				(path ""
					(reference "U6")
					(unit 1)
				)
			)
		)
	)
	(symbol
		(lib_id "antmicropower:GND")
		(at 116.84 215.9 0)
		(mirror y)
		(unit 1)
		(exclude_from_sim no)
		(in_bom yes)
		(on_board yes)
		(dnp no)
		(property "Reference" "#PWR032"
			(at 116.84 222.25 0)
			(effects
				(font
					(size 1.27 1.27)
				)
				(hide yes)
			)
		)
		(property "Value" "GND"
			(at 116.84 219.71 0)
			(effects
				(font
					(size 1.27 1.27)
				)
			)
		)
		(property "Footprint" ""
			(at 116.84 215.9 0)
			(effects
				(font
					(size 1.27 1.27)
				)
				(hide yes)
			)
		)
		(property "Datasheet" ""
			(at 116.84 215.9 0)
			(effects
				(font
					(size 1.27 1.27)
				)
				(hide yes)
			)
		)
		(property "Description" ""
			(at 116.84 215.9 0)
			(effects
				(font
					(size 1.27 1.27)
				)
				(hide yes)
			)
		)
		(property "Author" "Antmicro"
			(at 107.95 223.52 0)
			(effects
				(font
					(size 1.27 1.27)
					(thickness 0.15)
				)
				(justify left bottom)
				(hide yes)
			)
		)
		(property "License" "Apache-2.0"
			(at 107.95 226.06 0)
			(effects
				(font
					(size 1.27 1.27)
					(thickness 0.15)
				)
				(justify left bottom)
				(hide yes)
			)
		)
		(pin "1"
		)
		(instances
			(project "artix-dc-scm"
				(path ""
					(reference "#PWR032")
					(unit 1)
				)
			)
		)
	)
	(symbol
		(lib_id "antmicroResistors0402:R_357k_0402")
		(at 43.18 177.8 270)
		(unit 1)
		(exclude_from_sim no)
		(in_bom yes)
		(on_board yes)
		(dnp no)
		(property "Reference" "R48"
			(at 41.91 173.99 0)
			(effects
				(font
					(size 1.27 1.27)
				)
				(justify left)
			)
		)
		(property "Value" "R_357k_0402"
			(at 39.37 177.8 0)
			(effects
				(font
					(size 1.27 1.27)
				)
				(hide yes)
			)
		)
		(property "Footprint" "antmicro-footprints:R_0402_1005Metric"
			(at 27.94 198.12 0)
			(effects
				(font
					(size 1.27 1.27)
					(thickness 0.15)
				)
				(justify left bottom)
				(hide yes)
			)
		)
		(property "Datasheet" "https://www.bourns.com/docs/product-datasheets/cr.pdf"
			(at 25.4 198.12 0)
			(effects
				(font
					(size 1.27 1.27)
					(thickness 0.15)
				)
				(justify left bottom)
				(hide yes)
			)
		)
		(property "Description" "SMD Chip Resistor"
			(at 43.18 177.8 0)
			(effects
				(font
					(size 1.27 1.27)
				)
				(hide yes)
			)
		)
		(property "Manufacturer" "Bourns"
			(at 20.32 198.12 0)
			(effects
				(font
					(size 1.27 1.27)
					(thickness 0.15)
				)
				(justify left bottom)
				(hide yes)
			)
		)
		(property "MPN" "CR0402-FX-3573GLF"
			(at 22.86 198.12 0)
			(effects
				(font
					(size 1.27 1.27)
					(thickness 0.15)
				)
				(justify left bottom)
				(hide yes)
			)
		)
		(property "Val" "357k"
			(at 41.91 182.88 0)
			(effects
				(font
					(size 1.27 1.27)
					(thickness 0.15)
				)
				(justify left)
			)
		)
		(property "License" "Apache-2.0"
			(at 17.78 198.12 0)
			(effects
				(font
					(size 1.27 1.27)
					(thickness 0.15)
				)
				(justify left bottom)
				(hide yes)
			)
		)
		(property "Author" "Antmicro"
			(at 15.24 198.12 0)
			(effects
				(font
					(size 1.27 1.27)
					(thickness 0.15)
				)
				(justify left bottom)
				(hide yes)
			)
		)
		(property "Tolerance" "1%"
			(at 33.02 198.12 0)
			(effects
				(font
					(size 1.27 1.27)
				)
				(justify left bottom)
				(hide yes)
			)
		)
		(pin "1"
		)
		(pin "2"
		)
		(instances
			(project "artix-dc-scm"
				(path ""
					(reference "R48")
					(unit 1)
				)
			)
		)
	)
	(symbol
		(lib_id "antmicropower:GND")
		(at 226.06 67.31 0)
		(unit 1)
		(exclude_from_sim no)
		(in_bom yes)
		(on_board yes)
		(dnp no)
		(property "Reference" "#PWR028"
			(at 226.06 73.66 0)
			(effects
				(font
					(size 1.27 1.27)
				)
				(hide yes)
			)
		)
		(property "Value" "GND"
			(at 226.06 71.12 0)
			(effects
				(font
					(size 1.27 1.27)
				)
			)
		)
		(property "Footprint" ""
			(at 226.06 67.31 0)
			(effects
				(font
					(size 1.27 1.27)
				)
				(hide yes)
			)
		)
		(property "Datasheet" ""
			(at 226.06 67.31 0)
			(effects
				(font
					(size 1.27 1.27)
				)
				(hide yes)
			)
		)
		(property "Description" ""
			(at 226.06 67.31 0)
			(effects
				(font
					(size 1.27 1.27)
				)
				(hide yes)
			)
		)
		(property "Author" "Antmicro"
			(at 234.95 74.93 0)
			(effects
				(font
					(size 1.27 1.27)
					(thickness 0.15)
				)
				(justify left bottom)
				(hide yes)
			)
		)
		(property "License" "Apache-2.0"
			(at 234.95 77.47 0)
			(effects
				(font
					(size 1.27 1.27)
					(thickness 0.15)
				)
				(justify left bottom)
				(hide yes)
			)
		)
		(pin "1"
		)
		(instances
			(project "artix-dc-scm"
				(path ""
					(reference "#PWR028")
					(unit 1)
				)
			)
		)
	)
	(symbol
		(lib_id "antmicropower:GND")
		(at 261.62 67.31 0)
		(unit 1)
		(exclude_from_sim no)
		(in_bom yes)
		(on_board yes)
		(dnp no)
		(property "Reference" "#PWR029"
			(at 261.62 73.66 0)
			(effects
				(font
					(size 1.27 1.27)
				)
				(hide yes)
			)
		)
		(property "Value" "GND"
			(at 261.62 71.12 0)
			(effects
				(font
					(size 1.27 1.27)
				)
			)
		)
		(property "Footprint" ""
			(at 261.62 67.31 0)
			(effects
				(font
					(size 1.27 1.27)
				)
				(hide yes)
			)
		)
		(property "Datasheet" ""
			(at 261.62 67.31 0)
			(effects
				(font
					(size 1.27 1.27)
				)
				(hide yes)
			)
		)
		(property "Description" ""
			(at 261.62 67.31 0)
			(effects
				(font
					(size 1.27 1.27)
				)
				(hide yes)
			)
		)
		(property "Author" "Antmicro"
			(at 270.51 74.93 0)
			(effects
				(font
					(size 1.27 1.27)
					(thickness 0.15)
				)
				(justify left bottom)
				(hide yes)
			)
		)
		(property "License" "Apache-2.0"
			(at 270.51 77.47 0)
			(effects
				(font
					(size 1.27 1.27)
					(thickness 0.15)
				)
				(justify left bottom)
				(hide yes)
			)
		)
		(pin "1"
		)
		(instances
			(project "artix-dc-scm"
				(path ""
					(reference "#PWR029")
					(unit 1)
				)
			)
		)
	)
	(symbol
		(lib_id "antmicroGenericPinHeaders:PinHeader_1x6_P2.54mm_Drill1.1mm")
		(at 194.31 260.35 0)
		(unit 1)
		(exclude_from_sim no)
		(in_bom yes)
		(on_board yes)
		(dnp no)
		(property "Reference" "J7"
			(at 196.85 257.81 0)
			(effects
				(font
					(size 1.27 1.27)
				)
				(justify left)
			)
		)
		(property "Value" "PinHeader_1x6_P2.54mm_Drill1.1mm"
			(at 200.66 267.97 0)
			(effects
				(font
					(size 1.27 1.27)
					(thickness 0.15)
				)
				(justify left)
				(hide yes)
			)
		)
		(property "Footprint" "antmicro-footprints:PinHeader_1x6_P2.54mm_Drill1.1mm"
			(at 214.63 270.51 0)
			(effects
				(font
					(size 1.27 1.27)
					(thickness 0.15)
				)
				(justify left bottom)
				(hide yes)
			)
		)
		(property "Datasheet" "https://www.we-online.com/components/products/datasheet/61300611121.pdf"
			(at 214.63 273.05 0)
			(effects
				(font
					(size 1.27 1.27)
					(thickness 0.15)
				)
				(justify left bottom)
				(hide yes)
			)
		)
		(property "Description" "Pin Header, Vertical, Board-to-Board, 2.54 mm, 1 Rows, 6 Contacts, Through Hole Straight, WR-PHD"
			(at 194.31 260.35 0)
			(effects
				(font
					(size 1.27 1.27)
				)
				(hide yes)
			)
		)
		(property "MPN" "61300611121"
			(at 200.66 273.685 90)
			(effects
				(font
					(size 1.27 1.27)
					(thickness 0.15)
				)
				(justify left)
			)
		)
		(property "Manufacturer" "Würth Elektronik"
			(at 214.63 278.13 0)
			(effects
				(font
					(size 1.27 1.27)
					(thickness 0.15)
				)
				(justify left bottom)
				(hide yes)
			)
		)
		(property "Author" "Antmicro"
			(at 214.63 280.67 0)
			(effects
				(font
					(size 1.27 1.27)
					(thickness 0.15)
				)
				(justify left bottom)
				(hide yes)
			)
		)
		(property "License" "Apache-2.0"
			(at 214.63 283.21 0)
			(effects
				(font
					(size 1.27 1.27)
					(thickness 0.15)
				)
				(justify left bottom)
				(hide yes)
			)
		)
		(pin "1"
		)
		(pin "2"
		)
		(pin "3"
		)
		(pin "4"
		)
		(pin "5"
		)
		(pin "6"
		)
		(instances
			(project "artix-dc-scm"
				(path ""
					(reference "J7")
					(unit 1)
				)
			)
		)
	)
	(symbol
		(lib_id "antmicropower:GND")
		(at 194.31 274.32 0)
		(unit 1)
		(exclude_from_sim no)
		(in_bom yes)
		(on_board yes)
		(dnp no)
		(property "Reference" "#PWR096"
			(at 194.31 280.67 0)
			(effects
				(font
					(size 1.27 1.27)
				)
				(hide yes)
			)
		)
		(property "Value" "GND"
			(at 194.31 278.13 0)
			(effects
				(font
					(size 1.27 1.27)
				)
			)
		)
		(property "Footprint" ""
			(at 194.31 274.32 0)
			(effects
				(font
					(size 1.27 1.27)
				)
				(hide yes)
			)
		)
		(property "Datasheet" ""
			(at 194.31 274.32 0)
			(effects
				(font
					(size 1.27 1.27)
				)
				(hide yes)
			)
		)
		(property "Description" ""
			(at 194.31 274.32 0)
			(effects
				(font
					(size 1.27 1.27)
				)
				(hide yes)
			)
		)
		(property "Author" "Antmicro"
			(at 203.2 281.94 0)
			(effects
				(font
					(size 1.27 1.27)
					(thickness 0.15)
				)
				(justify left bottom)
				(hide yes)
			)
		)
		(property "License" "Apache-2.0"
			(at 203.2 284.48 0)
			(effects
				(font
					(size 1.27 1.27)
					(thickness 0.15)
				)
				(justify left bottom)
				(hide yes)
			)
		)
		(pin "1"
		)
		(instances
			(project "artix-dc-scm"
				(path ""
					(reference "#PWR096")
					(unit 1)
				)
			)
		)
	)
	(symbol
		(lib_id "antmicropower:PWR_FLAG")
		(at 388.62 115.57 0)
		(unit 1)
		(exclude_from_sim no)
		(in_bom yes)
		(on_board yes)
		(dnp no)
		(property "Reference" "#FLG0115"
			(at 388.62 113.665 0)
			(effects
				(font
					(size 1.27 1.27)
				)
				(hide yes)
			)
		)
		(property "Value" "PWR_FLAG"
			(at 388.62 111.76 0)
			(effects
				(font
					(size 1.27 1.27)
				)
			)
		)
		(property "Footprint" ""
			(at 388.62 115.57 0)
			(effects
				(font
					(size 1.27 1.27)
				)
				(hide yes)
			)
		)
		(property "Datasheet" ""
			(at 388.62 115.57 0)
			(effects
				(font
					(size 1.27 1.27)
				)
				(hide yes)
			)
		)
		(property "Description" ""
			(at 388.62 115.57 0)
			(effects
				(font
					(size 1.27 1.27)
				)
				(hide yes)
			)
		)
		(pin "1"
		)
		(instances
			(project "artix-dc-scm"
				(path ""
					(reference "#FLG0115")
					(unit 1)
				)
			)
		)
	)
	(symbol
		(lib_id "antmicropower:GND")
		(at 27.94 27.94 0)
		(unit 1)
		(exclude_from_sim no)
		(in_bom yes)
		(on_board yes)
		(dnp no)
		(property "Reference" "#PWR0121"
			(at 27.94 34.29 0)
			(effects
				(font
					(size 1.27 1.27)
				)
				(hide yes)
			)
		)
		(property "Value" "GND"
			(at 27.94 31.75 0)
			(effects
				(font
					(size 1.27 1.27)
				)
			)
		)
		(property "Footprint" ""
			(at 27.94 27.94 0)
			(effects
				(font
					(size 1.27 1.27)
				)
				(hide yes)
			)
		)
		(property "Datasheet" ""
			(at 27.94 27.94 0)
			(effects
				(font
					(size 1.27 1.27)
				)
				(hide yes)
			)
		)
		(property "Description" ""
			(at 27.94 27.94 0)
			(effects
				(font
					(size 1.27 1.27)
				)
				(hide yes)
			)
		)
		(property "Author" "Antmicro"
			(at 36.83 35.56 0)
			(effects
				(font
					(size 1.27 1.27)
					(thickness 0.15)
				)
				(justify left bottom)
				(hide yes)
			)
		)
		(property "License" "Apache-2.0"
			(at 36.83 38.1 0)
			(effects
				(font
					(size 1.27 1.27)
					(thickness 0.15)
				)
				(justify left bottom)
				(hide yes)
			)
		)
		(pin "1"
		)
		(instances
			(project "artix-dc-scm"
				(path ""
					(reference "#PWR0121")
					(unit 1)
				)
			)
		)
	)
	(symbol
		(lib_id "antmicropower:GND")
		(at 50.8 236.22 0)
		(unit 1)
		(exclude_from_sim no)
		(in_bom yes)
		(on_board yes)
		(dnp no)
		(property "Reference" "#PWR0253"
			(at 50.8 242.57 0)
			(effects
				(font
					(size 1.27 1.27)
				)
				(hide yes)
			)
		)
		(property "Value" "GND"
			(at 50.8 240.03 0)
			(effects
				(font
					(size 1.27 1.27)
				)
			)
		)
		(property "Footprint" ""
			(at 50.8 236.22 0)
			(effects
				(font
					(size 1.27 1.27)
				)
				(hide yes)
			)
		)
		(property "Datasheet" ""
			(at 50.8 236.22 0)
			(effects
				(font
					(size 1.27 1.27)
				)
				(hide yes)
			)
		)
		(property "Description" ""
			(at 50.8 236.22 0)
			(effects
				(font
					(size 1.27 1.27)
				)
				(hide yes)
			)
		)
		(property "Author" "Antmicro"
			(at 59.69 243.84 0)
			(effects
				(font
					(size 1.27 1.27)
					(thickness 0.15)
				)
				(justify left bottom)
				(hide yes)
			)
		)
		(property "License" "Apache-2.0"
			(at 59.69 246.38 0)
			(effects
				(font
					(size 1.27 1.27)
					(thickness 0.15)
				)
				(justify left bottom)
				(hide yes)
			)
		)
		(pin "1"
		)
		(instances
			(project "artix-dc-scm"
				(path ""
					(reference "#PWR0253")
					(unit 1)
				)
			)
		)
	)
	(symbol
		(lib_id "antmicropower:GND")
		(at 55.88 27.94 0)
		(unit 1)
		(exclude_from_sim no)
		(in_bom yes)
		(on_board yes)
		(dnp no)
		(property "Reference" "#PWR0267"
			(at 55.88 34.29 0)
			(effects
				(font
					(size 1.27 1.27)
				)
				(hide yes)
			)
		)
		(property "Value" "GND"
			(at 55.88 31.75 0)
			(effects
				(font
					(size 1.27 1.27)
				)
			)
		)
		(property "Footprint" ""
			(at 55.88 27.94 0)
			(effects
				(font
					(size 1.27 1.27)
				)
				(hide yes)
			)
		)
		(property "Datasheet" ""
			(at 55.88 27.94 0)
			(effects
				(font
					(size 1.27 1.27)
				)
				(hide yes)
			)
		)
		(property "Description" ""
			(at 55.88 27.94 0)
			(effects
				(font
					(size 1.27 1.27)
				)
				(hide yes)
			)
		)
		(property "Author" "Antmicro"
			(at 64.77 35.56 0)
			(effects
				(font
					(size 1.27 1.27)
					(thickness 0.15)
				)
				(justify left bottom)
				(hide yes)
			)
		)
		(property "License" "Apache-2.0"
			(at 64.77 38.1 0)
			(effects
				(font
					(size 1.27 1.27)
					(thickness 0.15)
				)
				(justify left bottom)
				(hide yes)
			)
		)
		(pin "1"
		)
		(instances
			(project "artix-dc-scm"
				(path ""
					(reference "#PWR0267")
					(unit 1)
				)
			)
		)
	)
	(symbol
		(lib_id "antmicropower:GND")
		(at 34.29 27.94 0)
		(unit 1)
		(exclude_from_sim no)
		(in_bom yes)
		(on_board yes)
		(dnp no)
		(property "Reference" "#PWR0261"
			(at 34.29 34.29 0)
			(effects
				(font
					(size 1.27 1.27)
				)
				(hide yes)
			)
		)
		(property "Value" "GND"
			(at 34.29 31.75 0)
			(effects
				(font
					(size 1.27 1.27)
				)
			)
		)
		(property "Footprint" ""
			(at 34.29 27.94 0)
			(effects
				(font
					(size 1.27 1.27)
				)
				(hide yes)
			)
		)
		(property "Datasheet" ""
			(at 34.29 27.94 0)
			(effects
				(font
					(size 1.27 1.27)
				)
				(hide yes)
			)
		)
		(property "Description" ""
			(at 34.29 27.94 0)
			(effects
				(font
					(size 1.27 1.27)
				)
				(hide yes)
			)
		)
		(property "Author" "Antmicro"
			(at 43.18 35.56 0)
			(effects
				(font
					(size 1.27 1.27)
					(thickness 0.15)
				)
				(justify left bottom)
				(hide yes)
			)
		)
		(property "License" "Apache-2.0"
			(at 43.18 38.1 0)
			(effects
				(font
					(size 1.27 1.27)
					(thickness 0.15)
				)
				(justify left bottom)
				(hide yes)
			)
		)
		(pin "1"
		)
		(instances
			(project "artix-dc-scm"
				(path ""
					(reference "#PWR0261")
					(unit 1)
				)
			)
		)
	)
	(symbol
		(lib_id "antmicropower:GND")
		(at 326.39 135.89 0)
		(unit 1)
		(exclude_from_sim no)
		(in_bom yes)
		(on_board yes)
		(dnp no)
		(property "Reference" "#PWR0271"
			(at 326.39 142.24 0)
			(effects
				(font
					(size 1.27 1.27)
				)
				(hide yes)
			)
		)
		(property "Value" "GND"
			(at 326.39 139.7 0)
			(effects
				(font
					(size 1.27 1.27)
				)
			)
		)
		(property "Footprint" ""
			(at 326.39 135.89 0)
			(effects
				(font
					(size 1.27 1.27)
				)
				(hide yes)
			)
		)
		(property "Datasheet" ""
			(at 326.39 135.89 0)
			(effects
				(font
					(size 1.27 1.27)
				)
				(hide yes)
			)
		)
		(property "Description" ""
			(at 326.39 135.89 0)
			(effects
				(font
					(size 1.27 1.27)
				)
				(hide yes)
			)
		)
		(property "Author" "Antmicro"
			(at 335.28 143.51 0)
			(effects
				(font
					(size 1.27 1.27)
					(thickness 0.15)
				)
				(justify left bottom)
				(hide yes)
			)
		)
		(property "License" "Apache-2.0"
			(at 335.28 146.05 0)
			(effects
				(font
					(size 1.27 1.27)
					(thickness 0.15)
				)
				(justify left bottom)
				(hide yes)
			)
		)
		(pin "1"
		)
		(instances
			(project "artix-dc-scm"
				(path ""
					(reference "#PWR0271")
					(unit 1)
				)
			)
		)
	)
	(symbol
		(lib_id "antmicropower:GND")
		(at 175.26 132.08 0)
		(unit 1)
		(exclude_from_sim no)
		(in_bom yes)
		(on_board yes)
		(dnp no)
		(property "Reference" "#PWR0249"
			(at 175.26 138.43 0)
			(effects
				(font
					(size 1.27 1.27)
				)
				(hide yes)
			)
		)
		(property "Value" "GND"
			(at 175.26 135.89 0)
			(effects
				(font
					(size 1.27 1.27)
				)
			)
		)
		(property "Footprint" ""
			(at 175.26 132.08 0)
			(effects
				(font
					(size 1.27 1.27)
				)
				(hide yes)
			)
		)
		(property "Datasheet" ""
			(at 175.26 132.08 0)
			(effects
				(font
					(size 1.27 1.27)
				)
				(hide yes)
			)
		)
		(property "Description" ""
			(at 175.26 132.08 0)
			(effects
				(font
					(size 1.27 1.27)
				)
				(hide yes)
			)
		)
		(property "Author" "Antmicro"
			(at 184.15 139.7 0)
			(effects
				(font
					(size 1.27 1.27)
					(thickness 0.15)
				)
				(justify left bottom)
				(hide yes)
			)
		)
		(property "License" "Apache-2.0"
			(at 184.15 142.24 0)
			(effects
				(font
					(size 1.27 1.27)
					(thickness 0.15)
				)
				(justify left bottom)
				(hide yes)
			)
		)
		(pin "1"
		)
		(instances
			(project "artix-dc-scm"
				(path ""
					(reference "#PWR0249")
					(unit 1)
				)
			)
		)
	)
	(symbol
		(lib_id "antmicroCapacitorsmisc:C_100n_6V3_0402")
		(at 48.26 27.94 90)
		(unit 1)
		(exclude_from_sim no)
		(in_bom yes)
		(on_board yes)
		(dnp no)
		(property "Reference" "C193"
			(at 48.895 23.495 90)
			(effects
				(font
					(size 1.27 1.27)
				)
				(justify right)
			)
		)
		(property "Value" "C_100n_6V3_0402"
			(at 58.42 7.62 0)
			(effects
				(font
					(size 1.27 1.27)
					(thickness 0.15)
				)
				(justify left bottom)
				(hide yes)
			)
		)
		(property "Footprint" "antmicro-footprints:C_0402_1005Metric"
			(at 60.96 7.62 0)
			(effects
				(font
					(size 1.27 1.27)
					(thickness 0.15)
				)
				(justify left bottom)
				(hide yes)
			)
		)
		(property "Datasheet" "https://www.passivecomponent.com/wp-content/uploads/datasheet/WTC_MLCC_General_Purpose.pdf"
			(at 63.5 7.62 0)
			(effects
				(font
					(size 1.27 1.27)
					(thickness 0.15)
				)
				(justify left bottom)
				(hide yes)
			)
		)
		(property "Description" "SMT Multilayer Ceramic Capacitor, 0.1 µF, 6.3 V, 0402 [1005 Metric], ± 10%, X5R, Walsin MLCC"
			(at 48.26 27.94 0)
			(effects
				(font
					(size 1.27 1.27)
				)
				(hide yes)
			)
		)
		(property "Manufacturer" "Walsin"
			(at 68.58 7.62 0)
			(effects
				(font
					(size 1.27 1.27)
					(thickness 0.15)
				)
				(justify left bottom)
				(hide yes)
			)
		)
		(property "MPN" "0402X104K6R3CT"
			(at 66.04 7.62 0)
			(effects
				(font
					(size 1.27 1.27)
					(thickness 0.15)
				)
				(justify left bottom)
				(hide yes)
			)
		)
		(property "Val" "100n"
			(at 48.895 27.305 90)
			(effects
				(font
					(size 1.27 1.27)
					(thickness 0.15)
				)
				(justify right)
			)
		)
		(property "License" "Apache-2.0"
			(at 71.12 7.62 0)
			(effects
				(font
					(size 1.27 1.27)
					(thickness 0.15)
				)
				(justify left bottom)
				(hide yes)
			)
		)
		(property "Author" "Antmicro"
			(at 73.66 7.62 0)
			(effects
				(font
					(size 1.27 1.27)
					(thickness 0.15)
				)
				(justify left bottom)
				(hide yes)
			)
		)
		(property "Voltage" ""
			(at 76.2 7.62 0)
			(effects
				(font
					(size 1.27 1.27)
				)
				(justify left bottom)
				(hide yes)
			)
		)
		(property "Dielectric" ""
			(at 78.74 7.62 0)
			(effects
				(font
					(size 1.27 1.27)
				)
				(justify left bottom)
				(hide yes)
			)
		)
		(property "Public" "False"
			(at 81.28 7.62 0)
			(effects
				(font
					(size 1.27 1.27)
				)
				(justify left bottom)
				(hide yes)
			)
		)
		(pin "1"
		)
		(pin "2"
		)
		(instances
			(project "artix-dc-scm"
				(path ""
					(reference "C193")
					(unit 1)
				)
			)
		)
	)
	(symbol
		(lib_id "antmicropower:GND")
		(at 41.91 43.18 0)
		(unit 1)
		(exclude_from_sim no)
		(in_bom yes)
		(on_board yes)
		(dnp no)
		(property "Reference" "#PWR0264"
			(at 41.91 49.53 0)
			(effects
				(font
					(size 1.27 1.27)
				)
				(hide yes)
			)
		)
		(property "Value" "GND"
			(at 41.91 46.99 0)
			(effects
				(font
					(size 1.27 1.27)
				)
			)
		)
		(property "Footprint" ""
			(at 41.91 43.18 0)
			(effects
				(font
					(size 1.27 1.27)
				)
				(hide yes)
			)
		)
		(property "Datasheet" ""
			(at 41.91 43.18 0)
			(effects
				(font
					(size 1.27 1.27)
				)
				(hide yes)
			)
		)
		(property "Description" ""
			(at 41.91 43.18 0)
			(effects
				(font
					(size 1.27 1.27)
				)
				(hide yes)
			)
		)
		(property "Author" "Antmicro"
			(at 50.8 50.8 0)
			(effects
				(font
					(size 1.27 1.27)
					(thickness 0.15)
				)
				(justify left bottom)
				(hide yes)
			)
		)
		(property "License" "Apache-2.0"
			(at 50.8 53.34 0)
			(effects
				(font
					(size 1.27 1.27)
					(thickness 0.15)
				)
				(justify left bottom)
				(hide yes)
			)
		)
		(pin "1"
		)
		(instances
			(project "artix-dc-scm"
				(path ""
					(reference "#PWR0264")
					(unit 1)
				)
			)
		)
	)
	(symbol
		(lib_id "antmicropower:PWR_FLAG")
		(at 95.25 172.72 270)
		(unit 1)
		(exclude_from_sim no)
		(in_bom yes)
		(on_board yes)
		(dnp no)
		(property "Reference" "#FLG0113"
			(at 97.155 172.72 0)
			(effects
				(font
					(size 1.27 1.27)
				)
				(hide yes)
			)
		)
		(property "Value" "PWR_FLAG"
			(at 102.87 172.72 90)
			(effects
				(font
					(size 1.27 1.27)
				)
			)
		)
		(property "Footprint" ""
			(at 95.25 172.72 0)
			(effects
				(font
					(size 1.27 1.27)
				)
				(hide yes)
			)
		)
		(property "Datasheet" ""
			(at 95.25 172.72 0)
			(effects
				(font
					(size 1.27 1.27)
				)
				(hide yes)
			)
		)
		(property "Description" ""
			(at 95.25 172.72 0)
			(effects
				(font
					(size 1.27 1.27)
				)
				(hide yes)
			)
		)
		(pin "1"
		)
		(instances
			(project "artix-dc-scm"
				(path ""
					(reference "#FLG0113")
					(unit 1)
				)
			)
		)
	)
	(symbol
		(lib_id "antmicropower:GND")
		(at 313.69 181.61 0)
		(unit 1)
		(exclude_from_sim no)
		(in_bom yes)
		(on_board yes)
		(dnp no)
		(property "Reference" "#PWR0272"
			(at 313.69 187.96 0)
			(effects
				(font
					(size 1.27 1.27)
				)
				(hide yes)
			)
		)
		(property "Value" "GND"
			(at 313.69 185.42 0)
			(effects
				(font
					(size 1.27 1.27)
				)
			)
		)
		(property "Footprint" ""
			(at 313.69 181.61 0)
			(effects
				(font
					(size 1.27 1.27)
				)
				(hide yes)
			)
		)
		(property "Datasheet" ""
			(at 313.69 181.61 0)
			(effects
				(font
					(size 1.27 1.27)
				)
				(hide yes)
			)
		)
		(property "Description" ""
			(at 313.69 181.61 0)
			(effects
				(font
					(size 1.27 1.27)
				)
				(hide yes)
			)
		)
		(property "Author" "Antmicro"
			(at 322.58 189.23 0)
			(effects
				(font
					(size 1.27 1.27)
					(thickness 0.15)
				)
				(justify left bottom)
				(hide yes)
			)
		)
		(property "License" "Apache-2.0"
			(at 322.58 191.77 0)
			(effects
				(font
					(size 1.27 1.27)
					(thickness 0.15)
				)
				(justify left bottom)
				(hide yes)
			)
		)
		(pin "1"
		)
		(instances
			(project "artix-dc-scm"
				(path ""
					(reference "#PWR0272")
					(unit 1)
				)
			)
		)
	)
	(symbol
		(lib_id "antmicropower:GND")
		(at 400.05 123.19 0)
		(unit 1)
		(exclude_from_sim no)
		(in_bom yes)
		(on_board yes)
		(dnp no)
		(property "Reference" "#PWR0280"
			(at 400.05 129.54 0)
			(effects
				(font
					(size 1.27 1.27)
				)
				(hide yes)
			)
		)
		(property "Value" "GND"
			(at 400.05 127 0)
			(effects
				(font
					(size 1.27 1.27)
				)
			)
		)
		(property "Footprint" ""
			(at 400.05 123.19 0)
			(effects
				(font
					(size 1.27 1.27)
				)
				(hide yes)
			)
		)
		(property "Datasheet" ""
			(at 400.05 123.19 0)
			(effects
				(font
					(size 1.27 1.27)
				)
				(hide yes)
			)
		)
		(property "Description" ""
			(at 400.05 123.19 0)
			(effects
				(font
					(size 1.27 1.27)
				)
				(hide yes)
			)
		)
		(property "Author" "Antmicro"
			(at 408.94 130.81 0)
			(effects
				(font
					(size 1.27 1.27)
					(thickness 0.15)
				)
				(justify left bottom)
				(hide yes)
			)
		)
		(property "License" "Apache-2.0"
			(at 408.94 133.35 0)
			(effects
				(font
					(size 1.27 1.27)
					(thickness 0.15)
				)
				(justify left bottom)
				(hide yes)
			)
		)
		(pin "1"
		)
		(instances
			(project "artix-dc-scm"
				(path ""
					(reference "#PWR0280")
					(unit 1)
				)
			)
		)
	)
	(symbol
		(lib_id "antmicroCapacitors0603:C_4u7_0603")
		(at 34.29 27.94 90)
		(unit 1)
		(exclude_from_sim no)
		(in_bom yes)
		(on_board yes)
		(dnp no)
		(property "Reference" "C191"
			(at 34.925 23.495 90)
			(effects
				(font
					(size 1.27 1.27)
				)
				(justify right)
			)
		)
		(property "Value" "C_4u7_0603"
			(at 44.45 7.62 0)
			(effects
				(font
					(size 1.27 1.27)
					(thickness 0.15)
				)
				(justify left bottom)
				(hide yes)
			)
		)
		(property "Footprint" "antmicro-footprints:C_0603_1608Metric"
			(at 46.99 7.62 0)
			(effects
				(font
					(size 1.27 1.27)
					(thickness 0.15)
				)
				(justify left bottom)
				(hide yes)
			)
		)
		(property "Datasheet" "https://product.tdk.com/en/search/capacitor/ceramic/mlcc/info?part_no=C1608X5R1V475M080AC"
			(at 49.53 7.62 0)
			(effects
				(font
					(size 1.27 1.27)
					(thickness 0.15)
				)
				(justify left bottom)
				(hide yes)
			)
		)
		(property "Description" "SMD Multilayer Ceramic Capacitor, 4.7 µF, 35 V, 0603 [1608 Metric], ± 20%, X5R, C"
			(at 34.29 27.94 0)
			(effects
				(font
					(size 1.27 1.27)
				)
				(hide yes)
			)
		)
		(property "Manufacturer" "TDK"
			(at 54.61 7.62 0)
			(effects
				(font
					(size 1.27 1.27)
					(thickness 0.15)
				)
				(justify left bottom)
				(hide yes)
			)
		)
		(property "MPN" "C1608X5R1V475M080AC"
			(at 52.07 7.62 0)
			(effects
				(font
					(size 1.27 1.27)
					(thickness 0.15)
				)
				(justify left bottom)
				(hide yes)
			)
		)
		(property "Val" "4u7"
			(at 34.925 27.305 90)
			(effects
				(font
					(size 1.27 1.27)
					(thickness 0.15)
				)
				(justify right)
			)
		)
		(property "License" "Apache-2.0"
			(at 57.15 7.62 0)
			(effects
				(font
					(size 1.27 1.27)
					(thickness 0.15)
				)
				(justify left bottom)
				(hide yes)
			)
		)
		(property "Author" "Antmicro"
			(at 59.69 7.62 0)
			(effects
				(font
					(size 1.27 1.27)
					(thickness 0.15)
				)
				(justify left bottom)
				(hide yes)
			)
		)
		(property "Voltage" ""
			(at 62.23 7.62 0)
			(effects
				(font
					(size 1.27 1.27)
				)
				(justify left bottom)
				(hide yes)
			)
		)
		(property "Dielectric" ""
			(at 64.77 7.62 0)
			(effects
				(font
					(size 1.27 1.27)
				)
				(justify left bottom)
				(hide yes)
			)
		)
		(pin "1"
		)
		(pin "2"
		)
		(instances
			(project "artix-dc-scm"
				(path ""
					(reference "C191")
					(unit 1)
				)
			)
		)
	)
	(symbol
		(lib_id "antmicropower:GND")
		(at 317.5 135.89 0)
		(unit 1)
		(exclude_from_sim no)
		(in_bom yes)
		(on_board yes)
		(dnp no)
		(property "Reference" "#PWR0270"
			(at 317.5 142.24 0)
			(effects
				(font
					(size 1.27 1.27)
				)
				(hide yes)
			)
		)
		(property "Value" "GND"
			(at 317.5 139.7 0)
			(effects
				(font
					(size 1.27 1.27)
				)
			)
		)
		(property "Footprint" ""
			(at 317.5 135.89 0)
			(effects
				(font
					(size 1.27 1.27)
				)
				(hide yes)
			)
		)
		(property "Datasheet" ""
			(at 317.5 135.89 0)
			(effects
				(font
					(size 1.27 1.27)
				)
				(hide yes)
			)
		)
		(property "Description" ""
			(at 317.5 135.89 0)
			(effects
				(font
					(size 1.27 1.27)
				)
				(hide yes)
			)
		)
		(property "Author" "Antmicro"
			(at 326.39 143.51 0)
			(effects
				(font
					(size 1.27 1.27)
					(thickness 0.15)
				)
				(justify left bottom)
				(hide yes)
			)
		)
		(property "License" "Apache-2.0"
			(at 326.39 146.05 0)
			(effects
				(font
					(size 1.27 1.27)
					(thickness 0.15)
				)
				(justify left bottom)
				(hide yes)
			)
		)
		(pin "1"
		)
		(instances
			(project "artix-dc-scm"
				(path ""
					(reference "#PWR0270")
					(unit 1)
				)
			)
		)
	)
	(symbol
		(lib_id "antmicropower:GND")
		(at 393.7 123.19 0)
		(unit 1)
		(exclude_from_sim no)
		(in_bom yes)
		(on_board yes)
		(dnp no)
		(property "Reference" "#PWR0279"
			(at 393.7 129.54 0)
			(effects
				(font
					(size 1.27 1.27)
				)
				(hide yes)
			)
		)
		(property "Value" "GND"
			(at 393.7 127 0)
			(effects
				(font
					(size 1.27 1.27)
				)
			)
		)
		(property "Footprint" ""
			(at 393.7 123.19 0)
			(effects
				(font
					(size 1.27 1.27)
				)
				(hide yes)
			)
		)
		(property "Datasheet" ""
			(at 393.7 123.19 0)
			(effects
				(font
					(size 1.27 1.27)
				)
				(hide yes)
			)
		)
		(property "Description" ""
			(at 393.7 123.19 0)
			(effects
				(font
					(size 1.27 1.27)
				)
				(hide yes)
			)
		)
		(property "Author" "Antmicro"
			(at 402.59 130.81 0)
			(effects
				(font
					(size 1.27 1.27)
					(thickness 0.15)
				)
				(justify left bottom)
				(hide yes)
			)
		)
		(property "License" "Apache-2.0"
			(at 402.59 133.35 0)
			(effects
				(font
					(size 1.27 1.27)
					(thickness 0.15)
				)
				(justify left bottom)
				(hide yes)
			)
		)
		(pin "1"
		)
		(instances
			(project "artix-dc-scm"
				(path ""
					(reference "#PWR0279")
					(unit 1)
				)
			)
		)
	)
	(symbol
		(lib_id "antmicroCapacitorsmisc:C_100n_6V3_0402")
		(at 27.94 43.18 90)
		(unit 1)
		(exclude_from_sim no)
		(in_bom yes)
		(on_board yes)
		(dnp no)
		(property "Reference" "C134"
			(at 28.575 38.735 90)
			(effects
				(font
					(size 1.27 1.27)
				)
				(justify right)
			)
		)
		(property "Value" "C_100n_6V3_0402"
			(at 38.1 22.86 0)
			(effects
				(font
					(size 1.27 1.27)
					(thickness 0.15)
				)
				(justify left bottom)
				(hide yes)
			)
		)
		(property "Footprint" "antmicro-footprints:C_0402_1005Metric"
			(at 40.64 22.86 0)
			(effects
				(font
					(size 1.27 1.27)
					(thickness 0.15)
				)
				(justify left bottom)
				(hide yes)
			)
		)
		(property "Datasheet" "https://www.passivecomponent.com/wp-content/uploads/datasheet/WTC_MLCC_General_Purpose.pdf"
			(at 43.18 22.86 0)
			(effects
				(font
					(size 1.27 1.27)
					(thickness 0.15)
				)
				(justify left bottom)
				(hide yes)
			)
		)
		(property "Description" "SMT Multilayer Ceramic Capacitor, 0.1 µF, 6.3 V, 0402 [1005 Metric], ± 10%, X5R, Walsin MLCC"
			(at 27.94 43.18 0)
			(effects
				(font
					(size 1.27 1.27)
				)
				(hide yes)
			)
		)
		(property "Manufacturer" "Walsin"
			(at 48.26 22.86 0)
			(effects
				(font
					(size 1.27 1.27)
					(thickness 0.15)
				)
				(justify left bottom)
				(hide yes)
			)
		)
		(property "MPN" "0402X104K6R3CT"
			(at 45.72 22.86 0)
			(effects
				(font
					(size 1.27 1.27)
					(thickness 0.15)
				)
				(justify left bottom)
				(hide yes)
			)
		)
		(property "Val" "100n"
			(at 28.575 42.545 90)
			(effects
				(font
					(size 1.27 1.27)
					(thickness 0.15)
				)
				(justify right)
			)
		)
		(property "License" "Apache-2.0"
			(at 50.8 22.86 0)
			(effects
				(font
					(size 1.27 1.27)
					(thickness 0.15)
				)
				(justify left bottom)
				(hide yes)
			)
		)
		(property "Author" "Antmicro"
			(at 53.34 22.86 0)
			(effects
				(font
					(size 1.27 1.27)
					(thickness 0.15)
				)
				(justify left bottom)
				(hide yes)
			)
		)
		(property "Voltage" ""
			(at 55.88 22.86 0)
			(effects
				(font
					(size 1.27 1.27)
				)
				(justify left bottom)
				(hide yes)
			)
		)
		(property "Dielectric" ""
			(at 58.42 22.86 0)
			(effects
				(font
					(size 1.27 1.27)
				)
				(justify left bottom)
				(hide yes)
			)
		)
		(property "Public" "False"
			(at 60.96 22.86 0)
			(effects
				(font
					(size 1.27 1.27)
				)
				(justify left bottom)
				(hide yes)
			)
		)
		(pin "1"
		)
		(pin "2"
		)
		(instances
			(project "artix-dc-scm"
				(path ""
					(reference "C134")
					(unit 1)
				)
			)
		)
	)
	(symbol
		(lib_id "antmicroGenericPinHeaders:PinHeader_2x7_P2mm_Drill0.9mm_878311420")
		(at 227.33 50.8 0)
		(unit 1)
		(exclude_from_sim no)
		(in_bom yes)
		(on_board yes)
		(dnp no)
		(fields_autoplaced yes)
		(property "Reference" "J6"
			(at 232.41 44.45 0)
			(effects
				(font
					(size 1.27 1.27)
					(thickness 0.15)
				)
			)
		)
		(property "Value" "PinHeader_2x7_P2mm_Drill0.9mm_878311420"
			(at 252.73 55.88 0)
			(effects
				(font
					(size 1.27 1.27)
					(thickness 0.15)
				)
				(justify left bottom)
				(hide yes)
			)
		)
		(property "Footprint" "antmicro-footprints:PinHeader_2x7_P2mm_Drill0.9mm_878311420"
			(at 252.73 58.42 0)
			(effects
				(font
					(size 1.27 1.27)
					(thickness 0.15)
				)
				(justify left bottom)
				(hide yes)
			)
		)
		(property "Datasheet" "https://www.molex.com/en-us/products/part-detail-pdf/878311420?display=pdf"
			(at 252.73 60.96 0)
			(effects
				(font
					(size 1.27 1.27)
					(thickness 0.15)
				)
				(justify left bottom)
				(hide yes)
			)
		)
		(property "Description" "2.00mm Pitch, Milli-Grid PCB Header, Dual Row, Vertical, Through Hole, Shrouded, 14 Circuits, 0.38µm Gold (Au) Plating, with Center Polarization Slot, with Locking Window, without PCB Locator, Tube"
			(at 227.33 50.8 0)
			(effects
				(font
					(size 1.27 1.27)
				)
				(hide yes)
			)
		)
		(property "MPN" "878311420"
			(at 232.41 46.99 0)
			(effects
				(font
					(size 1.27 1.27)
					(thickness 0.15)
				)
			)
		)
		(property "Manufacturer" "Molex"
			(at 252.73 66.04 0)
			(effects
				(font
					(size 1.27 1.27)
					(thickness 0.15)
				)
				(justify left bottom)
				(hide yes)
			)
		)
		(property "Author" "Antmicro"
			(at 252.73 68.58 0)
			(effects
				(font
					(size 1.27 1.27)
					(thickness 0.15)
				)
				(justify left bottom)
				(hide yes)
			)
		)
		(property "License" "Apache-2.0"
			(at 252.73 71.12 0)
			(effects
				(font
					(size 1.27 1.27)
					(thickness 0.15)
				)
				(justify left bottom)
				(hide yes)
			)
		)
		(pin "14"
		)
		(pin "7"
		)
		(pin "3"
		)
		(pin "6"
		)
		(pin "5"
		)
		(pin "4"
		)
		(pin "9"
		)
		(pin "10"
		)
		(pin "11"
		)
		(pin "12"
		)
		(pin "13"
		)
		(pin "2"
		)
		(pin "1"
		)
		(pin "8"
		)
		(instances
			(project "artix-dc-scm"
				(path ""
					(reference "J6")
					(unit 1)
				)
			)
		)
	)
	(symbol
		(lib_id "antmicropower:GND")
		(at 400.05 134.62 0)
		(unit 1)
		(exclude_from_sim no)
		(in_bom yes)
		(on_board yes)
		(dnp no)
		(property "Reference" "#PWR0277"
			(at 400.05 140.97 0)
			(effects
				(font
					(size 1.27 1.27)
				)
				(hide yes)
			)
		)
		(property "Value" "GND"
			(at 400.05 138.43 0)
			(effects
				(font
					(size 1.27 1.27)
				)
			)
		)
		(property "Footprint" ""
			(at 400.05 134.62 0)
			(effects
				(font
					(size 1.27 1.27)
				)
				(hide yes)
			)
		)
		(property "Datasheet" ""
			(at 400.05 134.62 0)
			(effects
				(font
					(size 1.27 1.27)
				)
				(hide yes)
			)
		)
		(property "Description" ""
			(at 400.05 134.62 0)
			(effects
				(font
					(size 1.27 1.27)
				)
				(hide yes)
			)
		)
		(property "Author" "Antmicro"
			(at 408.94 142.24 0)
			(effects
				(font
					(size 1.27 1.27)
					(thickness 0.15)
				)
				(justify left bottom)
				(hide yes)
			)
		)
		(property "License" "Apache-2.0"
			(at 408.94 144.78 0)
			(effects
				(font
					(size 1.27 1.27)
					(thickness 0.15)
				)
				(justify left bottom)
				(hide yes)
			)
		)
		(pin "1"
		)
		(instances
			(project "artix-dc-scm"
				(path ""
					(reference "#PWR0277")
					(unit 1)
				)
			)
		)
	)
	(symbol
		(lib_id "antmicropower:GND")
		(at 43.18 236.22 0)
		(unit 1)
		(exclude_from_sim no)
		(in_bom yes)
		(on_board yes)
		(dnp no)
		(property "Reference" "#PWR0255"
			(at 43.18 242.57 0)
			(effects
				(font
					(size 1.27 1.27)
				)
				(hide yes)
			)
		)
		(property "Value" "GND"
			(at 43.18 240.03 0)
			(effects
				(font
					(size 1.27 1.27)
				)
			)
		)
		(property "Footprint" ""
			(at 43.18 236.22 0)
			(effects
				(font
					(size 1.27 1.27)
				)
				(hide yes)
			)
		)
		(property "Datasheet" ""
			(at 43.18 236.22 0)
			(effects
				(font
					(size 1.27 1.27)
				)
				(hide yes)
			)
		)
		(property "Description" ""
			(at 43.18 236.22 0)
			(effects
				(font
					(size 1.27 1.27)
				)
				(hide yes)
			)
		)
		(property "Author" "Antmicro"
			(at 52.07 243.84 0)
			(effects
				(font
					(size 1.27 1.27)
					(thickness 0.15)
				)
				(justify left bottom)
				(hide yes)
			)
		)
		(property "License" "Apache-2.0"
			(at 52.07 246.38 0)
			(effects
				(font
					(size 1.27 1.27)
					(thickness 0.15)
				)
				(justify left bottom)
				(hide yes)
			)
		)
		(pin "1"
		)
		(instances
			(project "artix-dc-scm"
				(path ""
					(reference "#PWR0255")
					(unit 1)
				)
			)
		)
	)
	(symbol
		(lib_id "antmicropower:GND")
		(at 386.08 123.19 0)
		(unit 1)
		(exclude_from_sim no)
		(in_bom yes)
		(on_board yes)
		(dnp no)
		(property "Reference" "#PWR0281"
			(at 386.08 129.54 0)
			(effects
				(font
					(size 1.27 1.27)
				)
				(hide yes)
			)
		)
		(property "Value" "GND"
			(at 386.08 127 0)
			(effects
				(font
					(size 1.27 1.27)
				)
			)
		)
		(property "Footprint" ""
			(at 386.08 123.19 0)
			(effects
				(font
					(size 1.27 1.27)
				)
				(hide yes)
			)
		)
		(property "Datasheet" ""
			(at 386.08 123.19 0)
			(effects
				(font
					(size 1.27 1.27)
				)
				(hide yes)
			)
		)
		(property "Description" ""
			(at 386.08 123.19 0)
			(effects
				(font
					(size 1.27 1.27)
				)
				(hide yes)
			)
		)
		(property "Author" "Antmicro"
			(at 394.97 130.81 0)
			(effects
				(font
					(size 1.27 1.27)
					(thickness 0.15)
				)
				(justify left bottom)
				(hide yes)
			)
		)
		(property "License" "Apache-2.0"
			(at 394.97 133.35 0)
			(effects
				(font
					(size 1.27 1.27)
					(thickness 0.15)
				)
				(justify left bottom)
				(hide yes)
			)
		)
		(pin "1"
		)
		(instances
			(project "artix-dc-scm"
				(path ""
					(reference "#PWR0281")
					(unit 1)
				)
			)
		)
	)
	(symbol
		(lib_id "antmicropower:GND")
		(at 326.39 44.45 0)
		(unit 1)
		(exclude_from_sim no)
		(in_bom yes)
		(on_board yes)
		(dnp no)
		(property "Reference" "#PWR0252"
			(at 326.39 50.8 0)
			(effects
				(font
					(size 1.27 1.27)
				)
				(hide yes)
			)
		)
		(property "Value" "GND"
			(at 326.39 48.26 0)
			(effects
				(font
					(size 1.27 1.27)
				)
			)
		)
		(property "Footprint" ""
			(at 326.39 44.45 0)
			(effects
				(font
					(size 1.27 1.27)
				)
				(hide yes)
			)
		)
		(property "Datasheet" ""
			(at 326.39 44.45 0)
			(effects
				(font
					(size 1.27 1.27)
				)
				(hide yes)
			)
		)
		(property "Description" ""
			(at 326.39 44.45 0)
			(effects
				(font
					(size 1.27 1.27)
				)
				(hide yes)
			)
		)
		(property "Author" "Antmicro"
			(at 335.28 52.07 0)
			(effects
				(font
					(size 1.27 1.27)
					(thickness 0.15)
				)
				(justify left bottom)
				(hide yes)
			)
		)
		(property "License" "Apache-2.0"
			(at 335.28 54.61 0)
			(effects
				(font
					(size 1.27 1.27)
					(thickness 0.15)
				)
				(justify left bottom)
				(hide yes)
			)
		)
		(pin "1"
		)
		(instances
			(project "artix-dc-scm"
				(path ""
					(reference "#PWR0252")
					(unit 1)
				)
			)
		)
	)
	(symbol
		(lib_id "antmicroInterfaceControllers:FT4232H_QFN")
		(at 184.15 31.75 0)
		(unit 1)
		(exclude_from_sim no)
		(in_bom yes)
		(on_board yes)
		(dnp no)
		(fields_autoplaced yes)
		(property "Reference" "U19"
			(at 198.12 22.86 0)
			(effects
				(font
					(size 1.27 1.27)
					(thickness 0.15)
				)
			)
		)
		(property "Value" "FT4232H_QFN"
			(at 227.33 39.37 0)
			(effects
				(font
					(size 1.27 1.27)
					(thickness 0.15)
				)
				(justify left bottom)
				(hide yes)
			)
		)
		(property "Footprint" "antmicro-footprints:QFN-64-1EP_9x9mm_P0.5mm"
			(at 227.33 41.91 0)
			(effects
				(font
					(size 1.27 1.27)
					(thickness 0.15)
				)
				(justify left bottom)
				(hide yes)
			)
		)
		(property "Datasheet" "https://www.ftdichip.com/Support/Documents/DataSheets/ICs/DS_FT4232H.pdf"
			(at 227.33 44.45 0)
			(effects
				(font
					(size 1.27 1.27)
					(thickness 0.15)
				)
				(justify left bottom)
				(hide yes)
			)
		)
		(property "Description" "Interface Bridges, USB to UART, MPSSE, 1.62 V, 1.98 V, QFN, 64 Pins, -40 °C"
			(at 184.15 31.75 0)
			(effects
				(font
					(size 1.27 1.27)
				)
				(hide yes)
			)
		)
		(property "Manufacturer" "FTDI Chip"
			(at 227.33 46.99 0)
			(effects
				(font
					(size 1.27 1.27)
					(thickness 0.15)
				)
				(justify left bottom)
				(hide yes)
			)
		)
		(property "MPN" "FT4232HQ-TRAY"
			(at 198.12 25.4 0)
			(effects
				(font
					(size 1.27 1.27)
					(thickness 0.15)
				)
			)
		)
		(property "Author" "Antmicro"
			(at 227.33 49.53 0)
			(effects
				(font
					(size 1.27 1.27)
					(thickness 0.15)
				)
				(justify left bottom)
				(hide yes)
			)
		)
		(property "License" "Apache-2.0"
			(at 227.33 52.07 0)
			(effects
				(font
					(size 1.27 1.27)
					(thickness 0.15)
				)
				(justify left bottom)
				(hide yes)
			)
		)
		(pin "23"
		)
		(pin "41"
		)
		(pin "26"
		)
		(pin "25"
		)
		(pin "24"
		)
		(pin "42"
		)
		(pin "40"
		)
		(pin "4"
		)
		(pin "31"
		)
		(pin "9"
		)
		(pin "59"
		)
		(pin "34"
		)
		(pin "6"
		)
		(pin "12"
		)
		(pin "38"
		)
		(pin "7"
		)
		(pin "3"
		)
		(pin "11"
		)
		(pin "14"
		)
		(pin "60"
		)
		(pin "39"
		)
		(pin "30"
		)
		(pin "65"
		)
		(pin "51"
		)
		(pin "15"
		)
		(pin "5"
		)
		(pin "2"
		)
		(pin "22"
		)
		(pin "37"
		)
		(pin "19"
		)
		(pin "46"
		)
		(pin "8"
		)
		(pin "56"
		)
		(pin "58"
		)
		(pin "36"
		)
		(pin "45"
		)
		(pin "63"
		)
		(pin "62"
		)
		(pin "64"
		)
		(pin "44"
		)
		(pin "20"
		)
		(pin "48"
		)
		(pin "61"
		)
		(pin "53"
		)
		(pin "17"
		)
		(pin "16"
		)
		(pin "18"
		)
		(pin "50"
		)
		(pin "27"
		)
		(pin "49"
		)
		(pin "52"
		)
		(pin "57"
		)
		(pin "21"
		)
		(pin "32"
		)
		(pin "43"
		)
		(pin "33"
		)
		(pin "35"
		)
		(pin "47"
		)
		(pin "10"
		)
		(pin "28"
		)
		(pin "55"
		)
		(pin "54"
		)
		(pin "1"
		)
		(pin "13"
		)
		(pin "29"
		)
		(instances
			(project "artix-dc-scm"
				(path ""
					(reference "U19")
					(unit 1)
				)
			)
		)
	)
	(symbol
		(lib_id "antmicropower:GND")
		(at 334.01 44.45 0)
		(unit 1)
		(exclude_from_sim no)
		(in_bom yes)
		(on_board yes)
		(dnp no)
		(property "Reference" "#PWR0251"
			(at 334.01 50.8 0)
			(effects
				(font
					(size 1.27 1.27)
				)
				(hide yes)
			)
		)
		(property "Value" "GND"
			(at 334.01 48.26 0)
			(effects
				(font
					(size 1.27 1.27)
				)
			)
		)
		(property "Footprint" ""
			(at 334.01 44.45 0)
			(effects
				(font
					(size 1.27 1.27)
				)
				(hide yes)
			)
		)
		(property "Datasheet" ""
			(at 334.01 44.45 0)
			(effects
				(font
					(size 1.27 1.27)
				)
				(hide yes)
			)
		)
		(property "Description" ""
			(at 334.01 44.45 0)
			(effects
				(font
					(size 1.27 1.27)
				)
				(hide yes)
			)
		)
		(property "Author" "Antmicro"
			(at 342.9 52.07 0)
			(effects
				(font
					(size 1.27 1.27)
					(thickness 0.15)
				)
				(justify left bottom)
				(hide yes)
			)
		)
		(property "License" "Apache-2.0"
			(at 342.9 54.61 0)
			(effects
				(font
					(size 1.27 1.27)
					(thickness 0.15)
				)
				(justify left bottom)
				(hide yes)
			)
		)
		(pin "1"
		)
		(instances
			(project "artix-dc-scm"
				(path ""
					(reference "#PWR0251")
					(unit 1)
				)
			)
		)
	)
	(symbol
		(lib_id "antmicropower:GND")
		(at 356.87 181.61 0)
		(unit 1)
		(exclude_from_sim no)
		(in_bom yes)
		(on_board yes)
		(dnp no)
		(property "Reference" "#PWR0275"
			(at 356.87 187.96 0)
			(effects
				(font
					(size 1.27 1.27)
				)
				(hide yes)
			)
		)
		(property "Value" "GND"
			(at 356.87 185.42 0)
			(effects
				(font
					(size 1.27 1.27)
				)
			)
		)
		(property "Footprint" ""
			(at 356.87 181.61 0)
			(effects
				(font
					(size 1.27 1.27)
				)
				(hide yes)
			)
		)
		(property "Datasheet" ""
			(at 356.87 181.61 0)
			(effects
				(font
					(size 1.27 1.27)
				)
				(hide yes)
			)
		)
		(property "Description" ""
			(at 356.87 181.61 0)
			(effects
				(font
					(size 1.27 1.27)
				)
				(hide yes)
			)
		)
		(property "Author" "Antmicro"
			(at 365.76 189.23 0)
			(effects
				(font
					(size 1.27 1.27)
					(thickness 0.15)
				)
				(justify left bottom)
				(hide yes)
			)
		)
		(property "License" "Apache-2.0"
			(at 365.76 191.77 0)
			(effects
				(font
					(size 1.27 1.27)
					(thickness 0.15)
				)
				(justify left bottom)
				(hide yes)
			)
		)
		(pin "1"
		)
		(instances
			(project "artix-dc-scm"
				(path ""
					(reference "#PWR0275")
					(unit 1)
				)
			)
		)
	)
	(symbol
		(lib_id "antmicropower:PWR_FLAG")
		(at 181.61 20.32 0)
		(unit 1)
		(exclude_from_sim no)
		(in_bom yes)
		(on_board yes)
		(dnp no)
		(property "Reference" "#FLG0110"
			(at 181.61 18.415 0)
			(effects
				(font
					(size 1.27 1.27)
				)
				(hide yes)
			)
		)
		(property "Value" "PWR_FLAG"
			(at 181.61 16.51 0)
			(effects
				(font
					(size 1.27 1.27)
				)
			)
		)
		(property "Footprint" ""
			(at 181.61 20.32 0)
			(effects
				(font
					(size 1.27 1.27)
				)
				(hide yes)
			)
		)
		(property "Datasheet" ""
			(at 181.61 20.32 0)
			(effects
				(font
					(size 1.27 1.27)
				)
				(hide yes)
			)
		)
		(property "Description" ""
			(at 181.61 20.32 0)
			(effects
				(font
					(size 1.27 1.27)
				)
				(hide yes)
			)
		)
		(pin "1"
		)
		(instances
			(project "artix-dc-scm"
				(path ""
					(reference "#FLG0110")
					(unit 1)
				)
			)
		)
	)
	(symbol
		(lib_id "antmicropower:GND")
		(at 143.51 93.98 0)
		(unit 1)
		(exclude_from_sim no)
		(in_bom yes)
		(on_board yes)
		(dnp no)
		(property "Reference" "#PWR0260"
			(at 143.51 100.33 0)
			(effects
				(font
					(size 1.27 1.27)
				)
				(hide yes)
			)
		)
		(property "Value" "GND"
			(at 143.51 97.79 0)
			(effects
				(font
					(size 1.27 1.27)
				)
			)
		)
		(property "Footprint" ""
			(at 143.51 93.98 0)
			(effects
				(font
					(size 1.27 1.27)
				)
				(hide yes)
			)
		)
		(property "Datasheet" ""
			(at 143.51 93.98 0)
			(effects
				(font
					(size 1.27 1.27)
				)
				(hide yes)
			)
		)
		(property "Description" ""
			(at 143.51 93.98 0)
			(effects
				(font
					(size 1.27 1.27)
				)
				(hide yes)
			)
		)
		(property "Author" "Antmicro"
			(at 152.4 101.6 0)
			(effects
				(font
					(size 1.27 1.27)
					(thickness 0.15)
				)
				(justify left bottom)
				(hide yes)
			)
		)
		(property "License" "Apache-2.0"
			(at 152.4 104.14 0)
			(effects
				(font
					(size 1.27 1.27)
					(thickness 0.15)
				)
				(justify left bottom)
				(hide yes)
			)
		)
		(pin "1"
		)
		(instances
			(project "artix-dc-scm"
				(path ""
					(reference "#PWR0260")
					(unit 1)
				)
			)
		)
	)
	(symbol
		(lib_id "antmicropower:GND")
		(at 322.58 181.61 0)
		(unit 1)
		(exclude_from_sim no)
		(in_bom yes)
		(on_board yes)
		(dnp no)
		(property "Reference" "#PWR0273"
			(at 322.58 187.96 0)
			(effects
				(font
					(size 1.27 1.27)
				)
				(hide yes)
			)
		)
		(property "Value" "GND"
			(at 322.58 185.42 0)
			(effects
				(font
					(size 1.27 1.27)
				)
			)
		)
		(property "Footprint" ""
			(at 322.58 181.61 0)
			(effects
				(font
					(size 1.27 1.27)
				)
				(hide yes)
			)
		)
		(property "Datasheet" ""
			(at 322.58 181.61 0)
			(effects
				(font
					(size 1.27 1.27)
				)
				(hide yes)
			)
		)
		(property "Description" ""
			(at 322.58 181.61 0)
			(effects
				(font
					(size 1.27 1.27)
				)
				(hide yes)
			)
		)
		(property "Author" "Antmicro"
			(at 331.47 189.23 0)
			(effects
				(font
					(size 1.27 1.27)
					(thickness 0.15)
				)
				(justify left bottom)
				(hide yes)
			)
		)
		(property "License" "Apache-2.0"
			(at 331.47 191.77 0)
			(effects
				(font
					(size 1.27 1.27)
					(thickness 0.15)
				)
				(justify left bottom)
				(hide yes)
			)
		)
		(pin "1"
		)
		(instances
			(project "artix-dc-scm"
				(path ""
					(reference "#PWR0273")
					(unit 1)
				)
			)
		)
	)
	(symbol
		(lib_id "antmicropower:PWR_FLAG")
		(at 156.21 25.4 0)
		(unit 1)
		(exclude_from_sim no)
		(in_bom yes)
		(on_board yes)
		(dnp no)
		(property "Reference" "#FLG0111"
			(at 156.21 23.495 0)
			(effects
				(font
					(size 1.27 1.27)
				)
				(hide yes)
			)
		)
		(property "Value" "PWR_FLAG"
			(at 161.925 22.86 0)
			(effects
				(font
					(size 1.27 1.27)
				)
			)
		)
		(property "Footprint" ""
			(at 156.21 25.4 0)
			(effects
				(font
					(size 1.27 1.27)
				)
				(hide yes)
			)
		)
		(property "Datasheet" ""
			(at 156.21 25.4 0)
			(effects
				(font
					(size 1.27 1.27)
				)
				(hide yes)
			)
		)
		(property "Description" ""
			(at 156.21 25.4 0)
			(effects
				(font
					(size 1.27 1.27)
				)
				(hide yes)
			)
		)
		(pin "1"
		)
		(instances
			(project "artix-dc-scm"
				(path ""
					(reference "#FLG0111")
					(unit 1)
				)
			)
		)
	)
	(symbol
		(lib_id "antmicropower:PWR_FLAG")
		(at 58.42 257.81 90)
		(unit 1)
		(exclude_from_sim no)
		(in_bom yes)
		(on_board yes)
		(dnp no)
		(property "Reference" "#FLG0114"
			(at 56.515 257.81 0)
			(effects
				(font
					(size 1.27 1.27)
				)
				(hide yes)
			)
		)
		(property "Value" "PWR_FLAG"
			(at 50.8 257.81 90)
			(effects
				(font
					(size 1.27 1.27)
				)
			)
		)
		(property "Footprint" ""
			(at 58.42 257.81 0)
			(effects
				(font
					(size 1.27 1.27)
				)
				(hide yes)
			)
		)
		(property "Datasheet" ""
			(at 58.42 257.81 0)
			(effects
				(font
					(size 1.27 1.27)
				)
				(hide yes)
			)
		)
		(property "Description" ""
			(at 58.42 257.81 0)
			(effects
				(font
					(size 1.27 1.27)
				)
				(hide yes)
			)
		)
		(pin "1"
		)
		(instances
			(project "artix-dc-scm"
				(path ""
					(reference "#FLG0114")
					(unit 1)
				)
			)
		)
	)
	(symbol
		(lib_id "antmicropower:GND")
		(at 41.91 27.94 0)
		(unit 1)
		(exclude_from_sim no)
		(in_bom yes)
		(on_board yes)
		(dnp no)
		(property "Reference" "#PWR0266"
			(at 41.91 34.29 0)
			(effects
				(font
					(size 1.27 1.27)
				)
				(hide yes)
			)
		)
		(property "Value" "GND"
			(at 41.91 31.75 0)
			(effects
				(font
					(size 1.27 1.27)
				)
			)
		)
		(property "Footprint" ""
			(at 41.91 27.94 0)
			(effects
				(font
					(size 1.27 1.27)
				)
				(hide yes)
			)
		)
		(property "Datasheet" ""
			(at 41.91 27.94 0)
			(effects
				(font
					(size 1.27 1.27)
				)
				(hide yes)
			)
		)
		(property "Description" ""
			(at 41.91 27.94 0)
			(effects
				(font
					(size 1.27 1.27)
				)
				(hide yes)
			)
		)
		(property "Author" "Antmicro"
			(at 50.8 35.56 0)
			(effects
				(font
					(size 1.27 1.27)
					(thickness 0.15)
				)
				(justify left bottom)
				(hide yes)
			)
		)
		(property "License" "Apache-2.0"
			(at 50.8 38.1 0)
			(effects
				(font
					(size 1.27 1.27)
					(thickness 0.15)
				)
				(justify left bottom)
				(hide yes)
			)
		)
		(pin "1"
		)
		(instances
			(project "artix-dc-scm"
				(path ""
					(reference "#PWR0266")
					(unit 1)
				)
			)
		)
	)
	(symbol
		(lib_id "antmicropower:GND")
		(at 341.63 135.89 0)
		(unit 1)
		(exclude_from_sim no)
		(in_bom yes)
		(on_board yes)
		(dnp no)
		(property "Reference" "#PWR0268"
			(at 341.63 142.24 0)
			(effects
				(font
					(size 1.27 1.27)
				)
				(hide yes)
			)
		)
		(property "Value" "GND"
			(at 341.63 139.7 0)
			(effects
				(font
					(size 1.27 1.27)
				)
			)
		)
		(property "Footprint" ""
			(at 341.63 135.89 0)
			(effects
				(font
					(size 1.27 1.27)
				)
				(hide yes)
			)
		)
		(property "Datasheet" ""
			(at 341.63 135.89 0)
			(effects
				(font
					(size 1.27 1.27)
				)
				(hide yes)
			)
		)
		(property "Description" ""
			(at 341.63 135.89 0)
			(effects
				(font
					(size 1.27 1.27)
				)
				(hide yes)
			)
		)
		(property "Author" "Antmicro"
			(at 350.52 143.51 0)
			(effects
				(font
					(size 1.27 1.27)
					(thickness 0.15)
				)
				(justify left bottom)
				(hide yes)
			)
		)
		(property "License" "Apache-2.0"
			(at 350.52 146.05 0)
			(effects
				(font
					(size 1.27 1.27)
					(thickness 0.15)
				)
				(justify left bottom)
				(hide yes)
			)
		)
		(pin "1"
		)
		(instances
			(project "artix-dc-scm"
				(path ""
					(reference "#PWR0268")
					(unit 1)
				)
			)
		)
	)
	(symbol
		(lib_id "antmicropower:GND")
		(at 34.29 43.18 0)
		(unit 1)
		(exclude_from_sim no)
		(in_bom yes)
		(on_board yes)
		(dnp no)
		(property "Reference" "#PWR0262"
			(at 34.29 49.53 0)
			(effects
				(font
					(size 1.27 1.27)
				)
				(hide yes)
			)
		)
		(property "Value" "GND"
			(at 34.29 46.99 0)
			(effects
				(font
					(size 1.27 1.27)
				)
			)
		)
		(property "Footprint" ""
			(at 34.29 43.18 0)
			(effects
				(font
					(size 1.27 1.27)
				)
				(hide yes)
			)
		)
		(property "Datasheet" ""
			(at 34.29 43.18 0)
			(effects
				(font
					(size 1.27 1.27)
				)
				(hide yes)
			)
		)
		(property "Description" ""
			(at 34.29 43.18 0)
			(effects
				(font
					(size 1.27 1.27)
				)
				(hide yes)
			)
		)
		(property "Author" "Antmicro"
			(at 43.18 50.8 0)
			(effects
				(font
					(size 1.27 1.27)
					(thickness 0.15)
				)
				(justify left bottom)
				(hide yes)
			)
		)
		(property "License" "Apache-2.0"
			(at 43.18 53.34 0)
			(effects
				(font
					(size 1.27 1.27)
					(thickness 0.15)
				)
				(justify left bottom)
				(hide yes)
			)
		)
		(pin "1"
		)
		(instances
			(project "artix-dc-scm"
				(path ""
					(reference "#PWR0262")
					(unit 1)
				)
			)
		)
	)
	(symbol
		(lib_id "antmicropower:PWR_FLAG")
		(at 143.51 74.93 270)
		(unit 1)
		(exclude_from_sim no)
		(in_bom yes)
		(on_board yes)
		(dnp no)
		(property "Reference" "#FLG0112"
			(at 145.415 74.93 0)
			(effects
				(font
					(size 1.27 1.27)
				)
				(hide yes)
			)
		)
		(property "Value" "PWR_FLAG"
			(at 151.13 74.93 90)
			(effects
				(font
					(size 1.27 1.27)
				)
			)
		)
		(property "Footprint" ""
			(at 143.51 74.93 0)
			(effects
				(font
					(size 1.27 1.27)
				)
				(hide yes)
			)
		)
		(property "Datasheet" ""
			(at 143.51 74.93 0)
			(effects
				(font
					(size 1.27 1.27)
				)
				(hide yes)
			)
		)
		(property "Description" ""
			(at 143.51 74.93 0)
			(effects
				(font
					(size 1.27 1.27)
				)
				(hide yes)
			)
		)
		(pin "1"
		)
		(instances
			(project "artix-dc-scm"
				(path ""
					(reference "#FLG0112")
					(unit 1)
				)
			)
		)
	)
	(symbol
		(lib_id "antmicropower:GND")
		(at 35.56 236.22 0)
		(unit 1)
		(exclude_from_sim no)
		(in_bom yes)
		(on_board yes)
		(dnp no)
		(property "Reference" "#PWR0256"
			(at 35.56 242.57 0)
			(effects
				(font
					(size 1.27 1.27)
				)
				(hide yes)
			)
		)
		(property "Value" "GND"
			(at 35.56 240.03 0)
			(effects
				(font
					(size 1.27 1.27)
				)
			)
		)
		(property "Footprint" ""
			(at 35.56 236.22 0)
			(effects
				(font
					(size 1.27 1.27)
				)
				(hide yes)
			)
		)
		(property "Datasheet" ""
			(at 35.56 236.22 0)
			(effects
				(font
					(size 1.27 1.27)
				)
				(hide yes)
			)
		)
		(property "Description" ""
			(at 35.56 236.22 0)
			(effects
				(font
					(size 1.27 1.27)
				)
				(hide yes)
			)
		)
		(property "Author" "Antmicro"
			(at 44.45 243.84 0)
			(effects
				(font
					(size 1.27 1.27)
					(thickness 0.15)
				)
				(justify left bottom)
				(hide yes)
			)
		)
		(property "License" "Apache-2.0"
			(at 44.45 246.38 0)
			(effects
				(font
					(size 1.27 1.27)
					(thickness 0.15)
				)
				(justify left bottom)
				(hide yes)
			)
		)
		(pin "1"
		)
		(instances
			(project "artix-dc-scm"
				(path ""
					(reference "#PWR0256")
					(unit 1)
				)
			)
		)
	)
	(symbol
		(lib_id "antmicropower:GND")
		(at 27.94 236.22 0)
		(unit 1)
		(exclude_from_sim no)
		(in_bom yes)
		(on_board yes)
		(dnp no)
		(property "Reference" "#PWR0257"
			(at 27.94 242.57 0)
			(effects
				(font
					(size 1.27 1.27)
				)
				(hide yes)
			)
		)
		(property "Value" "GND"
			(at 27.94 240.03 0)
			(effects
				(font
					(size 1.27 1.27)
				)
			)
		)
		(property "Footprint" ""
			(at 27.94 236.22 0)
			(effects
				(font
					(size 1.27 1.27)
				)
				(hide yes)
			)
		)
		(property "Datasheet" ""
			(at 27.94 236.22 0)
			(effects
				(font
					(size 1.27 1.27)
				)
				(hide yes)
			)
		)
		(property "Description" ""
			(at 27.94 236.22 0)
			(effects
				(font
					(size 1.27 1.27)
				)
				(hide yes)
			)
		)
		(property "Author" "Antmicro"
			(at 36.83 243.84 0)
			(effects
				(font
					(size 1.27 1.27)
					(thickness 0.15)
				)
				(justify left bottom)
				(hide yes)
			)
		)
		(property "License" "Apache-2.0"
			(at 36.83 246.38 0)
			(effects
				(font
					(size 1.27 1.27)
					(thickness 0.15)
				)
				(justify left bottom)
				(hide yes)
			)
		)
		(pin "1"
		)
		(instances
			(project "artix-dc-scm"
				(path ""
					(reference "#PWR0257")
					(unit 1)
				)
			)
		)
	)
	(symbol
		(lib_id "antmicroCapacitors0603:C_4u7_0603")
		(at 41.91 43.18 90)
		(unit 1)
		(exclude_from_sim no)
		(in_bom yes)
		(on_board yes)
		(dnp no)
		(property "Reference" "C190"
			(at 42.545 38.735 90)
			(effects
				(font
					(size 1.27 1.27)
				)
				(justify right)
			)
		)
		(property "Value" "C_4u7_0603"
			(at 52.07 22.86 0)
			(effects
				(font
					(size 1.27 1.27)
					(thickness 0.15)
				)
				(justify left bottom)
				(hide yes)
			)
		)
		(property "Footprint" "antmicro-footprints:C_0603_1608Metric"
			(at 54.61 22.86 0)
			(effects
				(font
					(size 1.27 1.27)
					(thickness 0.15)
				)
				(justify left bottom)
				(hide yes)
			)
		)
		(property "Datasheet" "https://product.tdk.com/en/search/capacitor/ceramic/mlcc/info?part_no=C1608X5R1V475M080AC"
			(at 57.15 22.86 0)
			(effects
				(font
					(size 1.27 1.27)
					(thickness 0.15)
				)
				(justify left bottom)
				(hide yes)
			)
		)
		(property "Description" "SMD Multilayer Ceramic Capacitor, 4.7 µF, 35 V, 0603 [1608 Metric], ± 20%, X5R, C"
			(at 41.91 43.18 0)
			(effects
				(font
					(size 1.27 1.27)
				)
				(hide yes)
			)
		)
		(property "Manufacturer" "TDK"
			(at 62.23 22.86 0)
			(effects
				(font
					(size 1.27 1.27)
					(thickness 0.15)
				)
				(justify left bottom)
				(hide yes)
			)
		)
		(property "MPN" "C1608X5R1V475M080AC"
			(at 59.69 22.86 0)
			(effects
				(font
					(size 1.27 1.27)
					(thickness 0.15)
				)
				(justify left bottom)
				(hide yes)
			)
		)
		(property "Val" "4u7"
			(at 42.545 42.545 90)
			(effects
				(font
					(size 1.27 1.27)
					(thickness 0.15)
				)
				(justify right)
			)
		)
		(property "License" "Apache-2.0"
			(at 64.77 22.86 0)
			(effects
				(font
					(size 1.27 1.27)
					(thickness 0.15)
				)
				(justify left bottom)
				(hide yes)
			)
		)
		(property "Author" "Antmicro"
			(at 67.31 22.86 0)
			(effects
				(font
					(size 1.27 1.27)
					(thickness 0.15)
				)
				(justify left bottom)
				(hide yes)
			)
		)
		(property "Voltage" ""
			(at 69.85 22.86 0)
			(effects
				(font
					(size 1.27 1.27)
				)
				(justify left bottom)
				(hide yes)
			)
		)
		(property "Dielectric" ""
			(at 72.39 22.86 0)
			(effects
				(font
					(size 1.27 1.27)
				)
				(justify left bottom)
				(hide yes)
			)
		)
		(pin "1"
		)
		(pin "2"
		)
		(instances
			(project "artix-dc-scm"
				(path ""
					(reference "C190")
					(unit 1)
				)
			)
		)
	)
	(symbol
		(lib_id "antmicroCapacitorsmisc:C_100n_6V3_0402")
		(at 34.29 43.18 90)
		(unit 1)
		(exclude_from_sim no)
		(in_bom yes)
		(on_board yes)
		(dnp no)
		(property "Reference" "C136"
			(at 34.925 38.735 90)
			(effects
				(font
					(size 1.27 1.27)
				)
				(justify right)
			)
		)
		(property "Value" "C_100n_6V3_0402"
			(at 44.45 22.86 0)
			(effects
				(font
					(size 1.27 1.27)
					(thickness 0.15)
				)
				(justify left bottom)
				(hide yes)
			)
		)
		(property "Footprint" "antmicro-footprints:C_0402_1005Metric"
			(at 46.99 22.86 0)
			(effects
				(font
					(size 1.27 1.27)
					(thickness 0.15)
				)
				(justify left bottom)
				(hide yes)
			)
		)
		(property "Datasheet" "https://www.passivecomponent.com/wp-content/uploads/datasheet/WTC_MLCC_General_Purpose.pdf"
			(at 49.53 22.86 0)
			(effects
				(font
					(size 1.27 1.27)
					(thickness 0.15)
				)
				(justify left bottom)
				(hide yes)
			)
		)
		(property "Description" "SMT Multilayer Ceramic Capacitor, 0.1 µF, 6.3 V, 0402 [1005 Metric], ± 10%, X5R, Walsin MLCC"
			(at 34.29 43.18 0)
			(effects
				(font
					(size 1.27 1.27)
				)
				(hide yes)
			)
		)
		(property "Manufacturer" "Walsin"
			(at 54.61 22.86 0)
			(effects
				(font
					(size 1.27 1.27)
					(thickness 0.15)
				)
				(justify left bottom)
				(hide yes)
			)
		)
		(property "MPN" "0402X104K6R3CT"
			(at 52.07 22.86 0)
			(effects
				(font
					(size 1.27 1.27)
					(thickness 0.15)
				)
				(justify left bottom)
				(hide yes)
			)
		)
		(property "Val" "100n"
			(at 34.925 42.545 90)
			(effects
				(font
					(size 1.27 1.27)
					(thickness 0.15)
				)
				(justify right)
			)
		)
		(property "License" "Apache-2.0"
			(at 57.15 22.86 0)
			(effects
				(font
					(size 1.27 1.27)
					(thickness 0.15)
				)
				(justify left bottom)
				(hide yes)
			)
		)
		(property "Author" "Antmicro"
			(at 59.69 22.86 0)
			(effects
				(font
					(size 1.27 1.27)
					(thickness 0.15)
				)
				(justify left bottom)
				(hide yes)
			)
		)
		(property "Voltage" ""
			(at 62.23 22.86 0)
			(effects
				(font
					(size 1.27 1.27)
				)
				(justify left bottom)
				(hide yes)
			)
		)
		(property "Dielectric" ""
			(at 64.77 22.86 0)
			(effects
				(font
					(size 1.27 1.27)
				)
				(justify left bottom)
				(hide yes)
			)
		)
		(property "Public" "False"
			(at 67.31 22.86 0)
			(effects
				(font
					(size 1.27 1.27)
				)
				(justify left bottom)
				(hide yes)
			)
		)
		(pin "1"
		)
		(pin "2"
		)
		(instances
			(project "artix-dc-scm"
				(path ""
					(reference "C136")
					(unit 1)
				)
			)
		)
	)
	(symbol
		(lib_id "antmicropower:GND")
		(at 345.44 181.61 0)
		(unit 1)
		(exclude_from_sim no)
		(in_bom yes)
		(on_board yes)
		(dnp no)
		(property "Reference" "#PWR0276"
			(at 345.44 187.96 0)
			(effects
				(font
					(size 1.27 1.27)
				)
				(hide yes)
			)
		)
		(property "Value" "GND"
			(at 345.44 185.42 0)
			(effects
				(font
					(size 1.27 1.27)
				)
			)
		)
		(property "Footprint" ""
			(at 345.44 181.61 0)
			(effects
				(font
					(size 1.27 1.27)
				)
				(hide yes)
			)
		)
		(property "Datasheet" ""
			(at 345.44 181.61 0)
			(effects
				(font
					(size 1.27 1.27)
				)
				(hide yes)
			)
		)
		(property "Description" ""
			(at 345.44 181.61 0)
			(effects
				(font
					(size 1.27 1.27)
				)
				(hide yes)
			)
		)
		(property "Author" "Antmicro"
			(at 354.33 189.23 0)
			(effects
				(font
					(size 1.27 1.27)
					(thickness 0.15)
				)
				(justify left bottom)
				(hide yes)
			)
		)
		(property "License" "Apache-2.0"
			(at 354.33 191.77 0)
			(effects
				(font
					(size 1.27 1.27)
					(thickness 0.15)
				)
				(justify left bottom)
				(hide yes)
			)
		)
		(pin "1"
		)
		(instances
			(project "artix-dc-scm"
				(path ""
					(reference "#PWR0276")
					(unit 1)
				)
			)
		)
	)
	(symbol
		(lib_id "antmicropower:GND")
		(at 48.26 27.94 0)
		(unit 1)
		(exclude_from_sim no)
		(in_bom yes)
		(on_board yes)
		(dnp no)
		(property "Reference" "#PWR0265"
			(at 48.26 34.29 0)
			(effects
				(font
					(size 1.27 1.27)
				)
				(hide yes)
			)
		)
		(property "Value" "GND"
			(at 48.26 31.75 0)
			(effects
				(font
					(size 1.27 1.27)
				)
			)
		)
		(property "Footprint" ""
			(at 48.26 27.94 0)
			(effects
				(font
					(size 1.27 1.27)
				)
				(hide yes)
			)
		)
		(property "Datasheet" ""
			(at 48.26 27.94 0)
			(effects
				(font
					(size 1.27 1.27)
				)
				(hide yes)
			)
		)
		(property "Description" ""
			(at 48.26 27.94 0)
			(effects
				(font
					(size 1.27 1.27)
				)
				(hide yes)
			)
		)
		(property "Author" "Antmicro"
			(at 57.15 35.56 0)
			(effects
				(font
					(size 1.27 1.27)
					(thickness 0.15)
				)
				(justify left bottom)
				(hide yes)
			)
		)
		(property "License" "Apache-2.0"
			(at 57.15 38.1 0)
			(effects
				(font
					(size 1.27 1.27)
					(thickness 0.15)
				)
				(justify left bottom)
				(hide yes)
			)
		)
		(pin "1"
		)
		(instances
			(project "artix-dc-scm"
				(path ""
					(reference "#PWR0265")
					(unit 1)
				)
			)
		)
	)
	(symbol
		(lib_id "antmicropower:GND")
		(at 393.7 134.62 0)
		(unit 1)
		(exclude_from_sim no)
		(in_bom yes)
		(on_board yes)
		(dnp no)
		(property "Reference" "#PWR0278"
			(at 393.7 140.97 0)
			(effects
				(font
					(size 1.27 1.27)
				)
				(hide yes)
			)
		)
		(property "Value" "GND"
			(at 393.7 138.43 0)
			(effects
				(font
					(size 1.27 1.27)
				)
			)
		)
		(property "Footprint" ""
			(at 393.7 134.62 0)
			(effects
				(font
					(size 1.27 1.27)
				)
				(hide yes)
			)
		)
		(property "Datasheet" ""
			(at 393.7 134.62 0)
			(effects
				(font
					(size 1.27 1.27)
				)
				(hide yes)
			)
		)
		(property "Description" ""
			(at 393.7 134.62 0)
			(effects
				(font
					(size 1.27 1.27)
				)
				(hide yes)
			)
		)
		(property "Author" "Antmicro"
			(at 402.59 142.24 0)
			(effects
				(font
					(size 1.27 1.27)
					(thickness 0.15)
				)
				(justify left bottom)
				(hide yes)
			)
		)
		(property "License" "Apache-2.0"
			(at 402.59 144.78 0)
			(effects
				(font
					(size 1.27 1.27)
					(thickness 0.15)
				)
				(justify left bottom)
				(hide yes)
			)
		)
		(pin "1"
		)
		(instances
			(project "artix-dc-scm"
				(path ""
					(reference "#PWR0278")
					(unit 1)
				)
			)
		)
	)
	(symbol
		(lib_id "antmicropower:GND")
		(at 309.88 44.45 0)
		(unit 1)
		(exclude_from_sim no)
		(in_bom yes)
		(on_board yes)
		(dnp no)
		(property "Reference" "#PWR0258"
			(at 309.88 50.8 0)
			(effects
				(font
					(size 1.27 1.27)
				)
				(hide yes)
			)
		)
		(property "Value" "GND"
			(at 309.88 48.26 0)
			(effects
				(font
					(size 1.27 1.27)
				)
			)
		)
		(property "Footprint" ""
			(at 309.88 44.45 0)
			(effects
				(font
					(size 1.27 1.27)
				)
				(hide yes)
			)
		)
		(property "Datasheet" ""
			(at 309.88 44.45 0)
			(effects
				(font
					(size 1.27 1.27)
				)
				(hide yes)
			)
		)
		(property "Description" ""
			(at 309.88 44.45 0)
			(effects
				(font
					(size 1.27 1.27)
				)
				(hide yes)
			)
		)
		(property "Author" "Antmicro"
			(at 318.77 52.07 0)
			(effects
				(font
					(size 1.27 1.27)
					(thickness 0.15)
				)
				(justify left bottom)
				(hide yes)
			)
		)
		(property "License" "Apache-2.0"
			(at 318.77 54.61 0)
			(effects
				(font
					(size 1.27 1.27)
					(thickness 0.15)
				)
				(justify left bottom)
				(hide yes)
			)
		)
		(pin "1"
		)
		(instances
			(project "artix-dc-scm"
				(path ""
					(reference "#PWR0258")
					(unit 1)
				)
			)
		)
	)
	(symbol
		(lib_id "antmicropower:GND")
		(at 334.01 135.89 0)
		(unit 1)
		(exclude_from_sim no)
		(in_bom yes)
		(on_board yes)
		(dnp no)
		(property "Reference" "#PWR0269"
			(at 334.01 142.24 0)
			(effects
				(font
					(size 1.27 1.27)
				)
				(hide yes)
			)
		)
		(property "Value" "GND"
			(at 334.01 139.7 0)
			(effects
				(font
					(size 1.27 1.27)
				)
			)
		)
		(property "Footprint" ""
			(at 334.01 135.89 0)
			(effects
				(font
					(size 1.27 1.27)
				)
				(hide yes)
			)
		)
		(property "Datasheet" ""
			(at 334.01 135.89 0)
			(effects
				(font
					(size 1.27 1.27)
				)
				(hide yes)
			)
		)
		(property "Description" ""
			(at 334.01 135.89 0)
			(effects
				(font
					(size 1.27 1.27)
				)
				(hide yes)
			)
		)
		(property "Author" "Antmicro"
			(at 342.9 143.51 0)
			(effects
				(font
					(size 1.27 1.27)
					(thickness 0.15)
				)
				(justify left bottom)
				(hide yes)
			)
		)
		(property "License" "Apache-2.0"
			(at 342.9 146.05 0)
			(effects
				(font
					(size 1.27 1.27)
					(thickness 0.15)
				)
				(justify left bottom)
				(hide yes)
			)
		)
		(pin "1"
		)
		(instances
			(project "artix-dc-scm"
				(path ""
					(reference "#PWR0269")
					(unit 1)
				)
			)
		)
	)
	(symbol
		(lib_id "antmicropower:PWR_FLAG")
		(at 388.62 24.13 0)
		(unit 1)
		(exclude_from_sim no)
		(in_bom yes)
		(on_board yes)
		(dnp no)
		(property "Reference" "#FLG0109"
			(at 388.62 22.225 0)
			(effects
				(font
					(size 1.27 1.27)
				)
				(hide yes)
			)
		)
		(property "Value" "PWR_FLAG"
			(at 388.62 20.32 0)
			(effects
				(font
					(size 1.27 1.27)
				)
			)
		)
		(property "Footprint" ""
			(at 388.62 24.13 0)
			(effects
				(font
					(size 1.27 1.27)
				)
				(hide yes)
			)
		)
		(property "Datasheet" ""
			(at 388.62 24.13 0)
			(effects
				(font
					(size 1.27 1.27)
				)
				(hide yes)
			)
		)
		(property "Description" ""
			(at 388.62 24.13 0)
			(effects
				(font
					(size 1.27 1.27)
				)
				(hide yes)
			)
		)
		(pin "1"
		)
		(instances
			(project "artix-dc-scm"
				(path ""
					(reference "#FLG0109")
					(unit 1)
				)
			)
		)
	)
	(symbol
		(lib_id "antmicroResistors0402:R_100R_0402")
		(at 60.96 43.18 270)
		(mirror x)
		(unit 1)
		(exclude_from_sim no)
		(in_bom yes)
		(on_board yes)
		(dnp no)
		(property "Reference" "R143"
			(at 59.69 39.37 90)
			(effects
				(font
					(size 1.27 1.27)
				)
				(justify right)
			)
		)
		(property "Value" "R_100R_0402"
			(at 48.26 22.86 0)
			(effects
				(font
					(size 1.27 1.27)
					(thickness 0.15)
				)
				(justify left bottom)
				(hide yes)
			)
		)
		(property "Footprint" "antmicro-footprints:R_0402_1005Metric"
			(at 45.72 22.86 0)
			(effects
				(font
					(size 1.27 1.27)
					(thickness 0.15)
				)
				(justify left bottom)
				(hide yes)
			)
		)
		(property "Datasheet" "https://www.bourns.com/docs/product-datasheets/cr.pdf"
			(at 43.18 22.86 0)
			(effects
				(font
					(size 1.27 1.27)
					(thickness 0.15)
				)
				(justify left bottom)
				(hide yes)
			)
		)
		(property "Description" "SMD Chip Resistor, 100 ohm, ± 1%, 62.5 mW, 0402 [1005 Metric], Thick Film, General Purpose"
			(at 60.96 43.18 0)
			(effects
				(font
					(size 1.27 1.27)
				)
				(hide yes)
			)
		)
		(property "Manufacturer" "Bourns"
			(at 38.1 22.86 0)
			(effects
				(font
					(size 1.27 1.27)
					(thickness 0.15)
				)
				(justify left bottom)
				(hide yes)
			)
		)
		(property "MPN" "CR0402-FX-1000GLF"
			(at 40.64 22.86 0)
			(effects
				(font
					(size 1.27 1.27)
					(thickness 0.15)
				)
				(justify left bottom)
				(hide yes)
			)
		)
		(property "Val" "100R"
			(at 59.69 41.91 90)
			(effects
				(font
					(size 1.27 1.27)
					(thickness 0.15)
				)
				(justify right)
			)
		)
		(property "License" "Apache-2.0"
			(at 35.56 22.86 0)
			(effects
				(font
					(size 1.27 1.27)
					(thickness 0.15)
				)
				(justify left bottom)
				(hide yes)
			)
		)
		(property "Author" "Antmicro"
			(at 33.02 22.86 0)
			(effects
				(font
					(size 1.27 1.27)
					(thickness 0.15)
				)
				(justify left bottom)
				(hide yes)
			)
		)
		(property "Tolerance" "1%"
			(at 50.8 22.86 0)
			(effects
				(font
					(size 1.27 1.27)
				)
				(justify left bottom)
				(hide yes)
			)
		)
		(pin "1"
		)
		(pin "2"
		)
		(instances
			(project "artix-dc-scm"
				(path ""
					(reference "R143")
					(unit 1)
				)
			)
		)
	)
	(symbol
		(lib_id "antmicropower:GND")
		(at 58.42 264.16 0)
		(unit 1)
		(exclude_from_sim no)
		(in_bom yes)
		(on_board yes)
		(dnp no)
		(property "Reference" "#PWR0254"
			(at 58.42 270.51 0)
			(effects
				(font
					(size 1.27 1.27)
				)
				(hide yes)
			)
		)
		(property "Value" "GND"
			(at 58.42 267.97 0)
			(effects
				(font
					(size 1.27 1.27)
				)
			)
		)
		(property "Footprint" ""
			(at 58.42 264.16 0)
			(effects
				(font
					(size 1.27 1.27)
				)
				(hide yes)
			)
		)
		(property "Datasheet" ""
			(at 58.42 264.16 0)
			(effects
				(font
					(size 1.27 1.27)
				)
				(hide yes)
			)
		)
		(property "Description" ""
			(at 58.42 264.16 0)
			(effects
				(font
					(size 1.27 1.27)
				)
				(hide yes)
			)
		)
		(property "Author" "Antmicro"
			(at 67.31 271.78 0)
			(effects
				(font
					(size 1.27 1.27)
					(thickness 0.15)
				)
				(justify left bottom)
				(hide yes)
			)
		)
		(property "License" "Apache-2.0"
			(at 67.31 274.32 0)
			(effects
				(font
					(size 1.27 1.27)
					(thickness 0.15)
				)
				(justify left bottom)
				(hide yes)
			)
		)
		(pin "1"
		)
		(instances
			(project "artix-dc-scm"
				(path ""
					(reference "#PWR0254")
					(unit 1)
				)
			)
		)
	)
	(symbol
		(lib_id "antmicropower:GND")
		(at 27.94 43.18 0)
		(unit 1)
		(exclude_from_sim no)
		(in_bom yes)
		(on_board yes)
		(dnp no)
		(property "Reference" "#PWR0263"
			(at 27.94 49.53 0)
			(effects
				(font
					(size 1.27 1.27)
				)
				(hide yes)
			)
		)
		(property "Value" "GND"
			(at 27.94 46.99 0)
			(effects
				(font
					(size 1.27 1.27)
				)
			)
		)
		(property "Footprint" ""
			(at 27.94 43.18 0)
			(effects
				(font
					(size 1.27 1.27)
				)
				(hide yes)
			)
		)
		(property "Datasheet" ""
			(at 27.94 43.18 0)
			(effects
				(font
					(size 1.27 1.27)
				)
				(hide yes)
			)
		)
		(property "Description" ""
			(at 27.94 43.18 0)
			(effects
				(font
					(size 1.27 1.27)
				)
				(hide yes)
			)
		)
		(property "Author" "Antmicro"
			(at 36.83 50.8 0)
			(effects
				(font
					(size 1.27 1.27)
					(thickness 0.15)
				)
				(justify left bottom)
				(hide yes)
			)
		)
		(property "License" "Apache-2.0"
			(at 36.83 53.34 0)
			(effects
				(font
					(size 1.27 1.27)
					(thickness 0.15)
				)
				(justify left bottom)
				(hide yes)
			)
		)
		(pin "1"
		)
		(instances
			(project "artix-dc-scm"
				(path ""
					(reference "#PWR0263")
					(unit 1)
				)
			)
		)
	)
	(symbol
		(lib_id "antmicroCapacitorsmisc:C_100n_6V3_0402")
		(at 55.88 27.94 90)
		(unit 1)
		(exclude_from_sim no)
		(in_bom yes)
		(on_board yes)
		(dnp no)
		(property "Reference" "C241"
			(at 56.515 23.495 90)
			(effects
				(font
					(size 1.27 1.27)
				)
				(justify right)
			)
		)
		(property "Value" "C_100n_6V3_0402"
			(at 66.04 7.62 0)
			(effects
				(font
					(size 1.27 1.27)
					(thickness 0.15)
				)
				(justify left bottom)
				(hide yes)
			)
		)
		(property "Footprint" "antmicro-footprints:C_0402_1005Metric"
			(at 68.58 7.62 0)
			(effects
				(font
					(size 1.27 1.27)
					(thickness 0.15)
				)
				(justify left bottom)
				(hide yes)
			)
		)
		(property "Datasheet" "https://www.passivecomponent.com/wp-content/uploads/datasheet/WTC_MLCC_General_Purpose.pdf"
			(at 71.12 7.62 0)
			(effects
				(font
					(size 1.27 1.27)
					(thickness 0.15)
				)
				(justify left bottom)
				(hide yes)
			)
		)
		(property "Description" "SMT Multilayer Ceramic Capacitor, 0.1 µF, 6.3 V, 0402 [1005 Metric], ± 10%, X5R, Walsin MLCC"
			(at 55.88 27.94 0)
			(effects
				(font
					(size 1.27 1.27)
				)
				(hide yes)
			)
		)
		(property "Manufacturer" "Walsin"
			(at 76.2 7.62 0)
			(effects
				(font
					(size 1.27 1.27)
					(thickness 0.15)
				)
				(justify left bottom)
				(hide yes)
			)
		)
		(property "MPN" "0402X104K6R3CT"
			(at 73.66 7.62 0)
			(effects
				(font
					(size 1.27 1.27)
					(thickness 0.15)
				)
				(justify left bottom)
				(hide yes)
			)
		)
		(property "Val" "100n"
			(at 56.515 27.305 90)
			(effects
				(font
					(size 1.27 1.27)
					(thickness 0.15)
				)
				(justify right)
			)
		)
		(property "License" "Apache-2.0"
			(at 78.74 7.62 0)
			(effects
				(font
					(size 1.27 1.27)
					(thickness 0.15)
				)
				(justify left bottom)
				(hide yes)
			)
		)
		(property "Author" "Antmicro"
			(at 81.28 7.62 0)
			(effects
				(font
					(size 1.27 1.27)
					(thickness 0.15)
				)
				(justify left bottom)
				(hide yes)
			)
		)
		(property "Voltage" ""
			(at 83.82 7.62 0)
			(effects
				(font
					(size 1.27 1.27)
				)
				(justify left bottom)
				(hide yes)
			)
		)
		(property "Dielectric" ""
			(at 86.36 7.62 0)
			(effects
				(font
					(size 1.27 1.27)
				)
				(justify left bottom)
				(hide yes)
			)
		)
		(property "Public" "False"
			(at 88.9 7.62 0)
			(effects
				(font
					(size 1.27 1.27)
				)
				(justify left bottom)
				(hide yes)
			)
		)
		(pin "1"
		)
		(pin "2"
		)
		(instances
			(project "artix-dc-scm"
				(path ""
					(reference "C241")
					(unit 1)
				)
			)
		)
	)
	(symbol
		(lib_id "antmicropower:PWR_FLAG")
		(at 387.35 140.97 180)
		(unit 1)
		(exclude_from_sim no)
		(in_bom yes)
		(on_board yes)
		(dnp no)
		(property "Reference" "#FLG0116"
			(at 387.35 142.875 0)
			(effects
				(font
					(size 1.27 1.27)
				)
				(hide yes)
			)
		)
		(property "Value" "PWR_FLAG"
			(at 394.97 142.24 0)
			(effects
				(font
					(size 1.27 1.27)
				)
			)
		)
		(property "Footprint" ""
			(at 387.35 140.97 0)
			(effects
				(font
					(size 1.27 1.27)
				)
				(hide yes)
			)
		)
		(property "Datasheet" ""
			(at 387.35 140.97 0)
			(effects
				(font
					(size 1.27 1.27)
				)
				(hide yes)
			)
		)
		(property "Description" ""
			(at 387.35 140.97 0)
			(effects
				(font
					(size 1.27 1.27)
				)
				(hide yes)
			)
		)
		(pin "1"
		)
		(instances
			(project "artix-dc-scm"
				(path ""
					(reference "#FLG0116")
					(unit 1)
				)
			)
		)
	)
	(symbol
		(lib_id "antmicropower:GND")
		(at 213.36 132.08 0)
		(mirror y)
		(unit 1)
		(exclude_from_sim no)
		(in_bom yes)
		(on_board yes)
		(dnp no)
		(property "Reference" "#PWR0250"
			(at 213.36 138.43 0)
			(effects
				(font
					(size 1.27 1.27)
				)
				(hide yes)
			)
		)
		(property "Value" "GND"
			(at 213.36 135.89 0)
			(effects
				(font
					(size 1.27 1.27)
				)
			)
		)
		(property "Footprint" ""
			(at 213.36 132.08 0)
			(effects
				(font
					(size 1.27 1.27)
				)
				(hide yes)
			)
		)
		(property "Datasheet" ""
			(at 213.36 132.08 0)
			(effects
				(font
					(size 1.27 1.27)
				)
				(hide yes)
			)
		)
		(property "Description" ""
			(at 213.36 132.08 0)
			(effects
				(font
					(size 1.27 1.27)
				)
				(hide yes)
			)
		)
		(property "Author" "Antmicro"
			(at 204.47 139.7 0)
			(effects
				(font
					(size 1.27 1.27)
					(thickness 0.15)
				)
				(justify left bottom)
				(hide yes)
			)
		)
		(property "License" "Apache-2.0"
			(at 204.47 142.24 0)
			(effects
				(font
					(size 1.27 1.27)
					(thickness 0.15)
				)
				(justify left bottom)
				(hide yes)
			)
		)
		(pin "1"
		)
		(instances
			(project "artix-dc-scm"
				(path ""
					(reference "#PWR0250")
					(unit 1)
				)
			)
		)
	)
	(symbol
		(lib_id "antmicropower:PWR_FLAG")
		(at 387.35 48.26 180)
		(unit 1)
		(exclude_from_sim no)
		(in_bom yes)
		(on_board yes)
		(dnp no)
		(property "Reference" "#FLG0108"
			(at 387.35 50.165 0)
			(effects
				(font
					(size 1.27 1.27)
				)
				(hide yes)
			)
		)
		(property "Value" "PWR_FLAG"
			(at 393.7 50.8 0)
			(effects
				(font
					(size 1.27 1.27)
				)
			)
		)
		(property "Footprint" ""
			(at 387.35 48.26 0)
			(effects
				(font
					(size 1.27 1.27)
				)
				(hide yes)
			)
		)
		(property "Datasheet" ""
			(at 387.35 48.26 0)
			(effects
				(font
					(size 1.27 1.27)
				)
				(hide yes)
			)
		)
		(property "Description" ""
			(at 387.35 48.26 0)
			(effects
				(font
					(size 1.27 1.27)
				)
				(hide yes)
			)
		)
		(pin "1"
		)
		(instances
			(project "artix-dc-scm"
				(path ""
					(reference "#FLG0108")
					(unit 1)
				)
			)
		)
	)
	(symbol
		(lib_id "antmicropower:GND")
		(at 317.5 44.45 0)
		(unit 1)
		(exclude_from_sim no)
		(in_bom yes)
		(on_board yes)
		(dnp no)
		(property "Reference" "#PWR0259"
			(at 317.5 50.8 0)
			(effects
				(font
					(size 1.27 1.27)
				)
				(hide yes)
			)
		)
		(property "Value" "GND"
			(at 317.5 48.26 0)
			(effects
				(font
					(size 1.27 1.27)
				)
			)
		)
		(property "Footprint" ""
			(at 317.5 44.45 0)
			(effects
				(font
					(size 1.27 1.27)
				)
				(hide yes)
			)
		)
		(property "Datasheet" ""
			(at 317.5 44.45 0)
			(effects
				(font
					(size 1.27 1.27)
				)
				(hide yes)
			)
		)
		(property "Description" ""
			(at 317.5 44.45 0)
			(effects
				(font
					(size 1.27 1.27)
				)
				(hide yes)
			)
		)
		(property "Author" "Antmicro"
			(at 326.39 52.07 0)
			(effects
				(font
					(size 1.27 1.27)
					(thickness 0.15)
				)
				(justify left bottom)
				(hide yes)
			)
		)
		(property "License" "Apache-2.0"
			(at 326.39 54.61 0)
			(effects
				(font
					(size 1.27 1.27)
					(thickness 0.15)
				)
				(justify left bottom)
				(hide yes)
			)
		)
		(pin "1"
		)
		(instances
			(project "artix-dc-scm"
				(path ""
					(reference "#PWR0259")
					(unit 1)
				)
			)
		)
	)
	(symbol
		(lib_id "antmicroCapacitors0603:C_4u7_0603")
		(at 27.94 27.94 90)
		(unit 1)
		(exclude_from_sim no)
		(in_bom yes)
		(on_board yes)
		(dnp no)
		(property "Reference" "C45"
			(at 28.575 23.495 90)
			(effects
				(font
					(size 1.27 1.27)
				)
				(justify right)
			)
		)
		(property "Value" "C_4u7_0603"
			(at 38.1 7.62 0)
			(effects
				(font
					(size 1.27 1.27)
					(thickness 0.15)
				)
				(justify left bottom)
				(hide yes)
			)
		)
		(property "Footprint" "antmicro-footprints:C_0603_1608Metric"
			(at 40.64 7.62 0)
			(effects
				(font
					(size 1.27 1.27)
					(thickness 0.15)
				)
				(justify left bottom)
				(hide yes)
			)
		)
		(property "Datasheet" "https://product.tdk.com/en/search/capacitor/ceramic/mlcc/info?part_no=C1608X5R1V475M080AC"
			(at 43.18 7.62 0)
			(effects
				(font
					(size 1.27 1.27)
					(thickness 0.15)
				)
				(justify left bottom)
				(hide yes)
			)
		)
		(property "Description" "SMD Multilayer Ceramic Capacitor, 4.7 µF, 35 V, 0603 [1608 Metric], ± 20%, X5R, C"
			(at 27.94 27.94 0)
			(effects
				(font
					(size 1.27 1.27)
				)
				(hide yes)
			)
		)
		(property "Manufacturer" "TDK"
			(at 48.26 7.62 0)
			(effects
				(font
					(size 1.27 1.27)
					(thickness 0.15)
				)
				(justify left bottom)
				(hide yes)
			)
		)
		(property "MPN" "C1608X5R1V475M080AC"
			(at 45.72 7.62 0)
			(effects
				(font
					(size 1.27 1.27)
					(thickness 0.15)
				)
				(justify left bottom)
				(hide yes)
			)
		)
		(property "Val" "4u7"
			(at 28.575 27.305 90)
			(effects
				(font
					(size 1.27 1.27)
					(thickness 0.15)
				)
				(justify right)
			)
		)
		(property "License" "Apache-2.0"
			(at 50.8 7.62 0)
			(effects
				(font
					(size 1.27 1.27)
					(thickness 0.15)
				)
				(justify left bottom)
				(hide yes)
			)
		)
		(property "Author" "Antmicro"
			(at 53.34 7.62 0)
			(effects
				(font
					(size 1.27 1.27)
					(thickness 0.15)
				)
				(justify left bottom)
				(hide yes)
			)
		)
		(property "Voltage" ""
			(at 55.88 7.62 0)
			(effects
				(font
					(size 1.27 1.27)
				)
				(justify left bottom)
				(hide yes)
			)
		)
		(property "Dielectric" ""
			(at 58.42 7.62 0)
			(effects
				(font
					(size 1.27 1.27)
				)
				(justify left bottom)
				(hide yes)
			)
		)
		(pin "1"
		)
		(pin "2"
		)
		(instances
			(project "artix-dc-scm"
				(path ""
					(reference "C45")
					(unit 1)
				)
			)
		)
	)
	(symbol
		(lib_id "antmicropower:GND")
		(at 309.88 135.89 0)
		(unit 1)
		(exclude_from_sim no)
		(in_bom yes)
		(on_board yes)
		(dnp no)
		(property "Reference" "#PWR0274"
			(at 309.88 142.24 0)
			(effects
				(font
					(size 1.27 1.27)
				)
				(hide yes)
			)
		)
		(property "Value" "GND"
			(at 309.88 139.7 0)
			(effects
				(font
					(size 1.27 1.27)
				)
			)
		)
		(property "Footprint" ""
			(at 309.88 135.89 0)
			(effects
				(font
					(size 1.27 1.27)
				)
				(hide yes)
			)
		)
		(property "Datasheet" ""
			(at 309.88 135.89 0)
			(effects
				(font
					(size 1.27 1.27)
				)
				(hide yes)
			)
		)
		(property "Description" ""
			(at 309.88 135.89 0)
			(effects
				(font
					(size 1.27 1.27)
				)
				(hide yes)
			)
		)
		(property "Author" "Antmicro"
			(at 318.77 143.51 0)
			(effects
				(font
					(size 1.27 1.27)
					(thickness 0.15)
				)
				(justify left bottom)
				(hide yes)
			)
		)
		(property "License" "Apache-2.0"
			(at 318.77 146.05 0)
			(effects
				(font
					(size 1.27 1.27)
					(thickness 0.15)
				)
				(justify left bottom)
				(hide yes)
			)
		)
		(pin "1"
		)
		(instances
			(project "artix-dc-scm"
				(path ""
					(reference "#PWR0274")
					(unit 1)
				)
			)
		)
	)
	(symbol
		(lib_id "antmicroCapacitorsmisc:C_100n_6V3_0402")
		(at 41.91 27.94 90)
		(unit 1)
		(exclude_from_sim no)
		(in_bom yes)
		(on_board yes)
		(dnp no)
		(property "Reference" "C192"
			(at 42.545 23.495 90)
			(effects
				(font
					(size 1.27 1.27)
				)
				(justify right)
			)
		)
		(property "Value" "C_100n_6V3_0402"
			(at 52.07 7.62 0)
			(effects
				(font
					(size 1.27 1.27)
					(thickness 0.15)
				)
				(justify left bottom)
				(hide yes)
			)
		)
		(property "Footprint" "antmicro-footprints:C_0402_1005Metric"
			(at 54.61 7.62 0)
			(effects
				(font
					(size 1.27 1.27)
					(thickness 0.15)
				)
				(justify left bottom)
				(hide yes)
			)
		)
		(property "Datasheet" "https://www.passivecomponent.com/wp-content/uploads/datasheet/WTC_MLCC_General_Purpose.pdf"
			(at 57.15 7.62 0)
			(effects
				(font
					(size 1.27 1.27)
					(thickness 0.15)
				)
				(justify left bottom)
				(hide yes)
			)
		)
		(property "Description" "SMT Multilayer Ceramic Capacitor, 0.1 µF, 6.3 V, 0402 [1005 Metric], ± 10%, X5R, Walsin MLCC"
			(at 41.91 27.94 0)
			(effects
				(font
					(size 1.27 1.27)
				)
				(hide yes)
			)
		)
		(property "Manufacturer" "Walsin"
			(at 62.23 7.62 0)
			(effects
				(font
					(size 1.27 1.27)
					(thickness 0.15)
				)
				(justify left bottom)
				(hide yes)
			)
		)
		(property "MPN" "0402X104K6R3CT"
			(at 59.69 7.62 0)
			(effects
				(font
					(size 1.27 1.27)
					(thickness 0.15)
				)
				(justify left bottom)
				(hide yes)
			)
		)
		(property "Val" "100n"
			(at 42.545 27.305 90)
			(effects
				(font
					(size 1.27 1.27)
					(thickness 0.15)
				)
				(justify right)
			)
		)
		(property "License" "Apache-2.0"
			(at 64.77 7.62 0)
			(effects
				(font
					(size 1.27 1.27)
					(thickness 0.15)
				)
				(justify left bottom)
				(hide yes)
			)
		)
		(property "Author" "Antmicro"
			(at 67.31 7.62 0)
			(effects
				(font
					(size 1.27 1.27)
					(thickness 0.15)
				)
				(justify left bottom)
				(hide yes)
			)
		)
		(property "Voltage" ""
			(at 69.85 7.62 0)
			(effects
				(font
					(size 1.27 1.27)
				)
				(justify left bottom)
				(hide yes)
			)
		)
		(property "Dielectric" ""
			(at 72.39 7.62 0)
			(effects
				(font
					(size 1.27 1.27)
				)
				(justify left bottom)
				(hide yes)
			)
		)
		(property "Public" "False"
			(at 74.93 7.62 0)
			(effects
				(font
					(size 1.27 1.27)
				)
				(justify left bottom)
				(hide yes)
			)
		)
		(pin "1"
		)
		(pin "2"
		)
		(instances
			(project "artix-dc-scm"
				(path ""
					(reference "C192")
					(unit 1)
				)
			)
		)
	)
)
